FILE_TYPE = MACRO_DRAWING;
SET COLOR_WIRE YELLOW;
SET COLOR_PROP MONO;
SET COLOR_DOT WHITE;
SET COLOR_ARC YELLOW;
SET COLOR_BODY GREEN;
SET COLOR_NOTE MONO;
SET PROP_DISPLAY VALUE;
SET PAGE_NUMBER P53;
FORCEADD OFFPAGE..3
(1550 5250);
FORCEPROP 2 LAST $XR1 54 
J 0
(1854 5250);
DISPLAY 0.638298 (1854 5250);
PAINT MONO (1854 5250);
FORCEPROP 2 LAST $XR0 28 
J 0
(1764 5250);
DISPLAY 0.638298 (1764 5250);
PAINT MONO (1764 5250);
FORCEPROP 2 LAST CDS_LIB mstr_standard
J 0
(1550 5250);
DISPLAY 0.787234 (1550 5250);
PAINT MONO (1550 5250);
DISPLAY INVISIBLE (1550 5250);
FORCEPROP 1 LAST OFFPAGE TRUE
J 0
(1875 5125);
DISPLAY 0.936170 (1875 5125);
PAINT GREEN (1875 5125);
DISPLAY INVISIBLE (1875 5125);
FORCEPROP 1 LAST COMMENT_BODY TRUE
J 0
(1500 5150);
DISPLAY 0.936170 (1500 5150);
PAINT GREEN (1500 5150);
DISPLAY INVISIBLE (1500 5150);
FORCEPROP 2 LAST PATH I1
J 0
(1750 5325);
DISPLAY 0.787234 (1750 5325);
PAINT MONO (1750 5325);
DISPLAY INVISIBLE (1750 5325);
FORCEADD TAP..6
R 2
(650 5100);
FORCEPROP 3 LASTPIN (600 5100) SIG_NAME M_F_DQS_DP<16>
J 0
(610 5110);
DISPLAY 0.659574 (610 5110);
PAINT MONO (610 5110);
DISPLAY INVISIBLE (610 5110);
FORCEPROP 1 LASTPIN (600 5100) BN 16
J 2
(650 5110);
DISPLAY 0.617021 (650 5110);
PAINT PINK (650 5110);
FORCEPROP 2 LAST CDS_LIB mstr_standard
J 0
(650 5100);
DISPLAY 0.787234 (650 5100);
PAINT MONO (650 5100);
DISPLAY INVISIBLE (650 5100);
FORCEPROP 1 LAST BODY_TYPE PLUMBING
J 2
(650 5050);
DISPLAY 1.234043 (650 5050);
PAINT GREEN (650 5050);
DISPLAY INVISIBLE (650 5050);
FORCEPROP 1 LAST HDL_TAP TRUE
J 2
(325 4975);
DISPLAY 1.234043 (325 4975);
PAINT GREEN (325 4975);
DISPLAY INVISIBLE (325 4975);
FORCEPROP 1 LAST PATH I10
J 2
(650 5100);
DISPLAY 0.936170 (650 5100);
PAINT GREEN (650 5100);
DISPLAY INVISIBLE (650 5100);
FORCEADD TAP..6
R 2
(-1550 1825);
FORCEPROP 3 LASTPIN (-1600 1825) SIG_NAME M_F_DQ<11>
J 0
(-1590 1835);
DISPLAY 0.659574 (-1590 1835);
PAINT MONO (-1590 1835);
DISPLAY INVISIBLE (-1590 1835);
FORCEPROP 1 LASTPIN (-1600 1825) BN 11
J 2
(-1550 1835);
DISPLAY 0.617021 (-1550 1835);
PAINT PINK (-1550 1835);
FORCEPROP 2 LAST CDS_LIB mstr_standard
J 2
(-1550 1825);
DISPLAY 0.787234 (-1550 1825);
PAINT MONO (-1550 1825);
DISPLAY INVISIBLE (-1550 1825);
FORCEPROP 1 LAST BODY_TYPE PLUMBING
J 2
(-1550 1775);
DISPLAY 1.234043 (-1550 1775);
PAINT GREEN (-1550 1775);
DISPLAY INVISIBLE (-1550 1775);
FORCEPROP 1 LAST HDL_TAP TRUE
J 2
(-1875 1700);
DISPLAY 1.234043 (-1875 1700);
PAINT GREEN (-1875 1700);
DISPLAY INVISIBLE (-1875 1700);
FORCEPROP 1 LAST PATH I100
J 2
(-1550 1825);
DISPLAY 0.936170 (-1550 1825);
PAINT GREEN (-1550 1825);
DISPLAY INVISIBLE (-1550 1825);
FORCEADD TAP..6
R 2
(-1550 1775);
FORCEPROP 3 LASTPIN (-1600 1775) SIG_NAME M_F_DQ<8>
J 0
(-1590 1785);
DISPLAY 0.659574 (-1590 1785);
PAINT MONO (-1590 1785);
DISPLAY INVISIBLE (-1590 1785);
FORCEPROP 1 LASTPIN (-1600 1775) BN 8
J 2
(-1550 1785);
DISPLAY 0.617021 (-1550 1785);
PAINT PINK (-1550 1785);
FORCEPROP 2 LAST CDS_LIB mstr_standard
J 2
(-1550 1775);
DISPLAY 0.787234 (-1550 1775);
PAINT MONO (-1550 1775);
DISPLAY INVISIBLE (-1550 1775);
FORCEPROP 1 LAST BODY_TYPE PLUMBING
J 2
(-1550 1725);
DISPLAY 1.234043 (-1550 1725);
PAINT GREEN (-1550 1725);
DISPLAY INVISIBLE (-1550 1725);
FORCEPROP 1 LAST HDL_TAP TRUE
J 2
(-1875 1650);
DISPLAY 1.234043 (-1875 1650);
PAINT GREEN (-1875 1650);
DISPLAY INVISIBLE (-1875 1650);
FORCEPROP 1 LAST PATH I101
J 2
(-1550 1775);
DISPLAY 0.936170 (-1550 1775);
PAINT GREEN (-1550 1775);
DISPLAY INVISIBLE (-1550 1775);
FORCEADD TAP..6
R 2
(-1550 1675);
FORCEPROP 3 LASTPIN (-1600 1675) SIG_NAME M_F_DQ<6>
J 0
(-1590 1685);
DISPLAY 0.659574 (-1590 1685);
PAINT MONO (-1590 1685);
DISPLAY INVISIBLE (-1590 1685);
FORCEPROP 1 LASTPIN (-1600 1675) BN 6
J 2
(-1550 1685);
DISPLAY 0.617021 (-1550 1685);
PAINT PINK (-1550 1685);
FORCEPROP 2 LAST CDS_LIB mstr_standard
J 2
(-1550 1675);
DISPLAY 0.787234 (-1550 1675);
PAINT MONO (-1550 1675);
DISPLAY INVISIBLE (-1550 1675);
FORCEPROP 1 LAST BODY_TYPE PLUMBING
J 2
(-1550 1625);
DISPLAY 1.234043 (-1550 1625);
PAINT GREEN (-1550 1625);
DISPLAY INVISIBLE (-1550 1625);
FORCEPROP 1 LAST HDL_TAP TRUE
J 2
(-1875 1550);
DISPLAY 1.234043 (-1875 1550);
PAINT GREEN (-1875 1550);
DISPLAY INVISIBLE (-1875 1550);
FORCEPROP 1 LAST PATH I102
J 2
(-1550 1675);
DISPLAY 0.936170 (-1550 1675);
PAINT GREEN (-1550 1675);
DISPLAY INVISIBLE (-1550 1675);
FORCEADD TAP..6
R 2
(-1550 1725);
FORCEPROP 3 LASTPIN (-1600 1725) SIG_NAME M_F_DQ<9>
J 0
(-1590 1735);
DISPLAY 0.659574 (-1590 1735);
PAINT MONO (-1590 1735);
DISPLAY INVISIBLE (-1590 1735);
FORCEPROP 1 LASTPIN (-1600 1725) BN 9
J 2
(-1550 1735);
DISPLAY 0.617021 (-1550 1735);
PAINT PINK (-1550 1735);
FORCEPROP 2 LAST CDS_LIB mstr_standard
J 2
(-1550 1725);
DISPLAY 0.787234 (-1550 1725);
PAINT MONO (-1550 1725);
DISPLAY INVISIBLE (-1550 1725);
FORCEPROP 1 LAST BODY_TYPE PLUMBING
J 2
(-1550 1675);
DISPLAY 1.234043 (-1550 1675);
PAINT GREEN (-1550 1675);
DISPLAY INVISIBLE (-1550 1675);
FORCEPROP 1 LAST HDL_TAP TRUE
J 2
(-1875 1600);
DISPLAY 1.234043 (-1875 1600);
PAINT GREEN (-1875 1600);
DISPLAY INVISIBLE (-1875 1600);
FORCEPROP 1 LAST PATH I103
J 2
(-1550 1725);
DISPLAY 0.936170 (-1550 1725);
PAINT GREEN (-1550 1725);
DISPLAY INVISIBLE (-1550 1725);
FORCEADD TAP..6
R 2
(-1550 1625);
FORCEPROP 3 LASTPIN (-1600 1625) SIG_NAME M_F_DQ<7>
J 0
(-1590 1635);
DISPLAY 0.659574 (-1590 1635);
PAINT MONO (-1590 1635);
DISPLAY INVISIBLE (-1590 1635);
FORCEPROP 1 LASTPIN (-1600 1625) BN 7
J 2
(-1550 1635);
DISPLAY 0.617021 (-1550 1635);
PAINT PINK (-1550 1635);
FORCEPROP 2 LAST CDS_LIB mstr_standard
J 2
(-1550 1625);
DISPLAY 0.787234 (-1550 1625);
PAINT MONO (-1550 1625);
DISPLAY INVISIBLE (-1550 1625);
FORCEPROP 1 LAST BODY_TYPE PLUMBING
J 2
(-1550 1575);
DISPLAY 1.234043 (-1550 1575);
PAINT GREEN (-1550 1575);
DISPLAY INVISIBLE (-1550 1575);
FORCEPROP 1 LAST HDL_TAP TRUE
J 2
(-1875 1500);
DISPLAY 1.234043 (-1875 1500);
PAINT GREEN (-1875 1500);
DISPLAY INVISIBLE (-1875 1500);
FORCEPROP 1 LAST PATH I104
J 2
(-1550 1625);
DISPLAY 0.936170 (-1550 1625);
PAINT GREEN (-1550 1625);
DISPLAY INVISIBLE (-1550 1625);
FORCEADD TAP..6
R 2
(-1550 1575);
FORCEPROP 3 LASTPIN (-1600 1575) SIG_NAME M_F_DQ<4>
J 0
(-1590 1585);
DISPLAY 0.659574 (-1590 1585);
PAINT MONO (-1590 1585);
DISPLAY INVISIBLE (-1590 1585);
FORCEPROP 1 LASTPIN (-1600 1575) BN 4
J 2
(-1550 1585);
DISPLAY 0.617021 (-1550 1585);
PAINT PINK (-1550 1585);
FORCEPROP 2 LAST CDS_LIB mstr_standard
J 2
(-1550 1575);
DISPLAY 0.787234 (-1550 1575);
PAINT MONO (-1550 1575);
DISPLAY INVISIBLE (-1550 1575);
FORCEPROP 1 LAST BODY_TYPE PLUMBING
J 2
(-1550 1525);
DISPLAY 1.234043 (-1550 1525);
PAINT GREEN (-1550 1525);
DISPLAY INVISIBLE (-1550 1525);
FORCEPROP 1 LAST HDL_TAP TRUE
J 2
(-1875 1450);
DISPLAY 1.234043 (-1875 1450);
PAINT GREEN (-1875 1450);
DISPLAY INVISIBLE (-1875 1450);
FORCEPROP 1 LAST PATH I105
J 2
(-1550 1575);
DISPLAY 0.936170 (-1550 1575);
PAINT GREEN (-1550 1575);
DISPLAY INVISIBLE (-1550 1575);
FORCEADD TAP..6
R 2
(-1550 1475);
FORCEPROP 3 LASTPIN (-1600 1475) SIG_NAME M_F_DQ<2>
J 0
(-1590 1485);
DISPLAY 0.659574 (-1590 1485);
PAINT MONO (-1590 1485);
DISPLAY INVISIBLE (-1590 1485);
FORCEPROP 1 LASTPIN (-1600 1475) BN 2
J 2
(-1550 1485);
DISPLAY 0.617021 (-1550 1485);
PAINT PINK (-1550 1485);
FORCEPROP 2 LAST CDS_LIB mstr_standard
J 2
(-1550 1475);
DISPLAY 0.787234 (-1550 1475);
PAINT MONO (-1550 1475);
DISPLAY INVISIBLE (-1550 1475);
FORCEPROP 1 LAST BODY_TYPE PLUMBING
J 2
(-1550 1425);
DISPLAY 1.234043 (-1550 1425);
PAINT GREEN (-1550 1425);
DISPLAY INVISIBLE (-1550 1425);
FORCEPROP 1 LAST HDL_TAP TRUE
J 2
(-1875 1350);
DISPLAY 1.234043 (-1875 1350);
PAINT GREEN (-1875 1350);
DISPLAY INVISIBLE (-1875 1350);
FORCEPROP 1 LAST PATH I106
J 2
(-1550 1475);
DISPLAY 0.936170 (-1550 1475);
PAINT GREEN (-1550 1475);
DISPLAY INVISIBLE (-1550 1475);
FORCEADD TAP..6
R 2
(-1550 1525);
FORCEPROP 3 LASTPIN (-1600 1525) SIG_NAME M_F_DQ<5>
J 0
(-1590 1535);
DISPLAY 0.659574 (-1590 1535);
PAINT MONO (-1590 1535);
DISPLAY INVISIBLE (-1590 1535);
FORCEPROP 1 LASTPIN (-1600 1525) BN 5
J 2
(-1550 1535);
DISPLAY 0.617021 (-1550 1535);
PAINT PINK (-1550 1535);
FORCEPROP 2 LAST CDS_LIB mstr_standard
J 2
(-1550 1525);
DISPLAY 0.787234 (-1550 1525);
PAINT MONO (-1550 1525);
DISPLAY INVISIBLE (-1550 1525);
FORCEPROP 1 LAST BODY_TYPE PLUMBING
J 2
(-1550 1475);
DISPLAY 1.234043 (-1550 1475);
PAINT GREEN (-1550 1475);
DISPLAY INVISIBLE (-1550 1475);
FORCEPROP 1 LAST HDL_TAP TRUE
J 2
(-1875 1400);
DISPLAY 1.234043 (-1875 1400);
PAINT GREEN (-1875 1400);
DISPLAY INVISIBLE (-1875 1400);
FORCEPROP 1 LAST PATH I107
J 2
(-1550 1525);
DISPLAY 0.936170 (-1550 1525);
PAINT GREEN (-1550 1525);
DISPLAY INVISIBLE (-1550 1525);
FORCEADD TAP..6
R 2
(-1550 1375);
FORCEPROP 3 LASTPIN (-1600 1375) SIG_NAME M_F_DQ<0>
J 0
(-1590 1385);
DISPLAY 0.659574 (-1590 1385);
PAINT MONO (-1590 1385);
DISPLAY INVISIBLE (-1590 1385);
FORCEPROP 1 LASTPIN (-1600 1375) BN 0
J 2
(-1550 1385);
DISPLAY 0.617021 (-1550 1385);
PAINT PINK (-1550 1385);
FORCEPROP 2 LAST CDS_LIB mstr_standard
J 2
(-1550 1375);
DISPLAY 0.787234 (-1550 1375);
PAINT MONO (-1550 1375);
DISPLAY INVISIBLE (-1550 1375);
FORCEPROP 1 LAST BODY_TYPE PLUMBING
J 2
(-1550 1325);
DISPLAY 1.234043 (-1550 1325);
PAINT GREEN (-1550 1325);
DISPLAY INVISIBLE (-1550 1325);
FORCEPROP 1 LAST HDL_TAP TRUE
J 2
(-1875 1250);
DISPLAY 1.234043 (-1875 1250);
PAINT GREEN (-1875 1250);
DISPLAY INVISIBLE (-1875 1250);
FORCEPROP 1 LAST PATH I108
J 2
(-1550 1375);
DISPLAY 0.936170 (-1550 1375);
PAINT GREEN (-1550 1375);
DISPLAY INVISIBLE (-1550 1375);
FORCEADD TAP..6
R 2
(-1550 1425);
FORCEPROP 3 LASTPIN (-1600 1425) SIG_NAME M_F_DQ<3>
J 0
(-1590 1435);
DISPLAY 0.659574 (-1590 1435);
PAINT MONO (-1590 1435);
DISPLAY INVISIBLE (-1590 1435);
FORCEPROP 1 LASTPIN (-1600 1425) BN 3
J 2
(-1550 1435);
DISPLAY 0.617021 (-1550 1435);
PAINT PINK (-1550 1435);
FORCEPROP 2 LAST CDS_LIB mstr_standard
J 2
(-1550 1425);
DISPLAY 0.787234 (-1550 1425);
PAINT MONO (-1550 1425);
DISPLAY INVISIBLE (-1550 1425);
FORCEPROP 1 LAST BODY_TYPE PLUMBING
J 2
(-1550 1375);
DISPLAY 1.234043 (-1550 1375);
PAINT GREEN (-1550 1375);
DISPLAY INVISIBLE (-1550 1375);
FORCEPROP 1 LAST HDL_TAP TRUE
J 2
(-1875 1300);
DISPLAY 1.234043 (-1875 1300);
PAINT GREEN (-1875 1300);
DISPLAY INVISIBLE (-1875 1300);
FORCEPROP 1 LAST PATH I109
J 2
(-1550 1425);
DISPLAY 0.936170 (-1550 1425);
PAINT GREEN (-1550 1425);
DISPLAY INVISIBLE (-1550 1425);
FORCEADD TAP..6
R 2
(650 5000);
FORCEPROP 3 LASTPIN (600 5000) SIG_NAME M_F_DQS_DP<15>
J 0
(610 5010);
DISPLAY 0.659574 (610 5010);
PAINT MONO (610 5010);
DISPLAY INVISIBLE (610 5010);
FORCEPROP 1 LASTPIN (600 5000) BN 15
J 2
(650 5010);
DISPLAY 0.617021 (650 5010);
PAINT PINK (650 5010);
FORCEPROP 2 LAST CDS_LIB mstr_standard
J 0
(650 5000);
DISPLAY 0.787234 (650 5000);
PAINT MONO (650 5000);
DISPLAY INVISIBLE (650 5000);
FORCEPROP 1 LAST BODY_TYPE PLUMBING
J 2
(650 4950);
DISPLAY 1.234043 (650 4950);
PAINT GREEN (650 4950);
DISPLAY INVISIBLE (650 4950);
FORCEPROP 1 LAST HDL_TAP TRUE
J 2
(325 4875);
DISPLAY 1.234043 (325 4875);
PAINT GREEN (325 4875);
DISPLAY INVISIBLE (325 4875);
FORCEPROP 1 LAST PATH I11
J 2
(650 5000);
DISPLAY 0.936170 (650 5000);
PAINT GREEN (650 5000);
DISPLAY INVISIBLE (650 5000);
FORCEADD TAP..6
R 2
(-1550 1325);
FORCEPROP 3 LASTPIN (-1600 1325) SIG_NAME M_F_DQ<1>
J 0
(-1590 1335);
DISPLAY 0.659574 (-1590 1335);
PAINT MONO (-1590 1335);
DISPLAY INVISIBLE (-1590 1335);
FORCEPROP 1 LASTPIN (-1600 1325) BN 1
J 2
(-1550 1335);
DISPLAY 0.617021 (-1550 1335);
PAINT PINK (-1550 1335);
FORCEPROP 2 LAST CDS_LIB mstr_standard
J 2
(-1550 1325);
DISPLAY 0.787234 (-1550 1325);
PAINT MONO (-1550 1325);
DISPLAY INVISIBLE (-1550 1325);
FORCEPROP 1 LAST BODY_TYPE PLUMBING
J 2
(-1550 1275);
DISPLAY 1.234043 (-1550 1275);
PAINT GREEN (-1550 1275);
DISPLAY INVISIBLE (-1550 1275);
FORCEPROP 1 LAST HDL_TAP TRUE
J 2
(-1875 1200);
DISPLAY 1.234043 (-1875 1200);
PAINT GREEN (-1875 1200);
DISPLAY INVISIBLE (-1875 1200);
FORCEPROP 1 LAST PATH I110
J 2
(-1550 1325);
DISPLAY 0.936170 (-1550 1325);
PAINT GREEN (-1550 1325);
DISPLAY INVISIBLE (-1550 1325);
FORCEADD SCONN288_H44441004..1
(-2300 2825);
FORCEPROP 1 LAST PART_NUMBER H44441-004
J 0
(-2750 825);
DISPLAY 0.617021 (-2750 825);
PAINT BLUE (-2750 825);
FORCEPROP 2 LASTPIN (-2800 1325) $PN 146
J 2
(-2810 1335);
DISPLAY 0.617021 (-2810 1335);
PAINT ORANGE (-2810 1335);
FORCEPROP 2 LASTPIN (-2800 1675) $PN 284
J 2
(-2810 1685);
DISPLAY 0.617021 (-2810 1685);
PAINT ORANGE (-2810 1685);
FORCEPROP 2 LASTPIN (-2800 1475) $PN 285
J 2
(-2810 1485);
DISPLAY 0.617021 (-2810 1485);
PAINT ORANGE (-2810 1485);
FORCEPROP 2 LASTPIN (-2800 1425) $PN 141
J 2
(-2810 1435);
DISPLAY 0.617021 (-2810 1435);
PAINT ORANGE (-2810 1435);
FORCEPROP 2 LASTPIN (-2800 1025) $PN 230
J 2
(-2810 1035);
DISPLAY 0.617021 (-2810 1035);
PAINT ORANGE (-2810 1035);
FORCEPROP 2 LASTPIN (-2800 1625) $PN 238
J 2
(-2810 1635);
DISPLAY 0.617021 (-2810 1635);
PAINT ORANGE (-2810 1635);
FORCEPROP 2 LASTPIN (-2800 1575) $PN 140
J 2
(-2810 1585);
DISPLAY 0.617021 (-2810 1585);
PAINT ORANGE (-2810 1585);
FORCEPROP 2 LASTPIN (-2800 1525) $PN 139
J 2
(-2810 1535);
DISPLAY 0.617021 (-2810 1535);
PAINT ORANGE (-2810 1535);
FORCEPROP 2 LASTPIN (-2800 2975) $PN 237
J 2
(-2810 2985);
DISPLAY 0.617021 (-2810 2985);
PAINT ORANGE (-2810 2985);
FORCEPROP 2 LASTPIN (-2800 2925) $PN 93
J 2
(-2810 2935);
DISPLAY 0.617021 (-2810 2935);
PAINT ORANGE (-2810 2935);
FORCEPROP 2 LASTPIN (-2800 2875) $PN 89
J 2
(-2810 2885);
DISPLAY 0.617021 (-2810 2885);
PAINT ORANGE (-2810 2885);
FORCEPROP 2 LASTPIN (-2800 2825) $PN 84
J 2
(-2810 2835);
DISPLAY 0.617021 (-2810 2835);
PAINT ORANGE (-2810 2835);
FORCEPROP 2 LASTPIN (-2800 1225) $PN 144
J 2
(-2810 1235);
DISPLAY 0.617021 (-2810 1235);
PAINT ORANGE (-2810 1235);
FORCEPROP 2 LASTPIN (-2800 1175) $PN 227
J 2
(-2810 1185);
DISPLAY 0.617021 (-2810 1185);
PAINT ORANGE (-2810 1185);
FORCEPROP 2 LASTPIN (-2800 1125) $PN 205
J 2
(-2810 1135);
DISPLAY 0.617021 (-2810 1135);
PAINT ORANGE (-2810 1135);
FORCEPROP 2 LASTPIN (-2800 1925) $PN 58
J 2
(-2810 1935);
DISPLAY 0.617021 (-2810 1935);
PAINT ORANGE (-2810 1935);
FORCEPROP 2 LASTPIN (-2800 1975) $PN 222
J 2
(-2810 1985);
DISPLAY 0.617021 (-2810 1985);
PAINT ORANGE (-2810 1985);
FORCEPROP 2 LASTPIN (-2800 2575) $PN 91
J 2
(-2810 2585);
DISPLAY 0.617021 (-2810 2585);
PAINT ORANGE (-2810 2585);
FORCEPROP 2 LASTPIN (-2800 2525) $PN 87
J 2
(-2810 2535);
DISPLAY 0.617021 (-2810 2535);
PAINT ORANGE (-2810 2535);
FORCEPROP 2 LASTPIN (-2800 1875) $PN 78
J 2
(-2810 1885);
DISPLAY 0.617021 (-2810 1885);
PAINT ORANGE (-2810 1885);
FORCEPROP 2 LASTPIN (-1800 4475) $PN 280
J 0
(-1790 4485);
DISPLAY 0.617021 (-1790 4485);
PAINT ORANGE (-1790 4485);
FORCEPROP 2 LASTPIN (-1800 4425) $PN 135
J 0
(-1790 4435);
DISPLAY 0.617021 (-1790 4435);
PAINT ORANGE (-1790 4435);
FORCEPROP 2 LASTPIN (-1800 4375) $PN 273
J 0
(-1790 4385);
DISPLAY 0.617021 (-1790 4385);
PAINT ORANGE (-1790 4385);
FORCEPROP 2 LASTPIN (-1800 4275) $PN 282
J 0
(-1790 4285);
DISPLAY 0.617021 (-1790 4285);
PAINT ORANGE (-1790 4285);
FORCEPROP 2 LASTPIN (-1800 4225) $PN 137
J 0
(-1790 4235);
DISPLAY 0.617021 (-1790 4235);
PAINT ORANGE (-1790 4235);
FORCEPROP 2 LASTPIN (-1800 4175) $PN 275
J 0
(-1790 4185);
DISPLAY 0.617021 (-1790 4185);
PAINT ORANGE (-1790 4185);
FORCEPROP 2 LASTPIN (-1800 4075) $PN 269
J 0
(-1790 4085);
DISPLAY 0.617021 (-1790 4085);
PAINT ORANGE (-1790 4085);
FORCEPROP 2 LASTPIN (-1800 4025) $PN 124
J 0
(-1790 4035);
DISPLAY 0.617021 (-1790 4035);
PAINT ORANGE (-1790 4035);
FORCEPROP 2 LASTPIN (-1800 3975) $PN 262
J 0
(-1790 3985);
DISPLAY 0.617021 (-1790 3985);
PAINT ORANGE (-1790 3985);
FORCEPROP 2 LASTPIN (-1800 3925) $PN 117
J 0
(-1790 3935);
DISPLAY 0.617021 (-1790 3935);
PAINT ORANGE (-1790 3935);
FORCEPROP 2 LASTPIN (-1800 3875) $PN 271
J 0
(-1790 3885);
DISPLAY 0.617021 (-1790 3885);
PAINT ORANGE (-1790 3885);
FORCEPROP 2 LASTPIN (-1800 3825) $PN 126
J 0
(-1790 3835);
DISPLAY 0.617021 (-1790 3835);
PAINT ORANGE (-1790 3835);
FORCEPROP 2 LASTPIN (-1800 3775) $PN 264
J 0
(-1790 3785);
DISPLAY 0.617021 (-1790 3785);
PAINT ORANGE (-1790 3785);
FORCEPROP 2 LASTPIN (-1800 3725) $PN 119
J 0
(-1790 3735);
DISPLAY 0.617021 (-1790 3735);
PAINT ORANGE (-1790 3735);
FORCEPROP 2 LASTPIN (-1800 3675) $PN 258
J 0
(-1790 3685);
DISPLAY 0.617021 (-1790 3685);
PAINT ORANGE (-1790 3685);
FORCEPROP 2 LASTPIN (-1800 3625) $PN 113
J 0
(-1790 3635);
DISPLAY 0.617021 (-1790 3635);
PAINT ORANGE (-1790 3635);
FORCEPROP 2 LASTPIN (-1800 3575) $PN 251
J 0
(-1790 3585);
DISPLAY 0.617021 (-1790 3585);
PAINT ORANGE (-1790 3585);
FORCEPROP 2 LASTPIN (-1800 3525) $PN 106
J 0
(-1790 3535);
DISPLAY 0.617021 (-1790 3535);
PAINT ORANGE (-1790 3535);
FORCEPROP 2 LASTPIN (-1800 3475) $PN 260
J 0
(-1790 3485);
DISPLAY 0.617021 (-1790 3485);
PAINT ORANGE (-1790 3485);
FORCEPROP 2 LASTPIN (-1800 3375) $PN 253
J 0
(-1790 3385);
DISPLAY 0.617021 (-1790 3385);
PAINT ORANGE (-1790 3385);
FORCEPROP 2 LASTPIN (-1800 3325) $PN 108
J 0
(-1790 3335);
DISPLAY 0.617021 (-1790 3335);
PAINT ORANGE (-1790 3335);
FORCEPROP 2 LASTPIN (-1800 3275) $PN 247
J 0
(-1790 3285);
DISPLAY 0.617021 (-1790 3285);
PAINT ORANGE (-1790 3285);
FORCEPROP 2 LASTPIN (-1800 3225) $PN 102
J 0
(-1790 3235);
DISPLAY 0.617021 (-1790 3235);
PAINT ORANGE (-1790 3235);
FORCEPROP 2 LASTPIN (-1800 3175) $PN 240
J 0
(-1790 3185);
DISPLAY 0.617021 (-1790 3185);
PAINT ORANGE (-1790 3185);
FORCEPROP 2 LASTPIN (-1800 3125) $PN 95
J 0
(-1790 3135);
DISPLAY 0.617021 (-1790 3135);
PAINT ORANGE (-1790 3135);
FORCEPROP 2 LASTPIN (-1800 3075) $PN 249
J 0
(-1790 3085);
DISPLAY 0.617021 (-1790 3085);
PAINT ORANGE (-1790 3085);
FORCEPROP 2 LASTPIN (-1800 2925) $PN 97
J 0
(-1790 2935);
DISPLAY 0.617021 (-1790 2935);
PAINT ORANGE (-1790 2935);
FORCEPROP 2 LASTPIN (-1800 2775) $PN 181
J 0
(-1790 2785);
DISPLAY 0.617021 (-1790 2785);
PAINT ORANGE (-1790 2785);
FORCEPROP 2 LASTPIN (-1800 2725) $PN 36
J 0
(-1790 2735);
DISPLAY 0.617021 (-1790 2735);
PAINT ORANGE (-1790 2735);
FORCEPROP 2 LASTPIN (-1800 2675) $PN 190
J 0
(-1790 2685);
DISPLAY 0.617021 (-1790 2685);
PAINT ORANGE (-1790 2685);
FORCEPROP 2 LASTPIN (-1800 2625) $PN 45
J 0
(-1790 2635);
DISPLAY 0.617021 (-1790 2635);
PAINT ORANGE (-1790 2635);
FORCEPROP 2 LASTPIN (-1800 2575) $PN 183
J 0
(-1790 2585);
DISPLAY 0.617021 (-1790 2585);
PAINT ORANGE (-1790 2585);
FORCEPROP 2 LASTPIN (-1800 2525) $PN 38
J 0
(-1790 2535);
DISPLAY 0.617021 (-1790 2535);
PAINT ORANGE (-1790 2535);
FORCEPROP 2 LASTPIN (-1800 2475) $PN 177
J 0
(-1790 2485);
DISPLAY 0.617021 (-1790 2485);
PAINT ORANGE (-1790 2485);
FORCEPROP 2 LASTPIN (-1800 2425) $PN 32
J 0
(-1790 2435);
DISPLAY 0.617021 (-1790 2435);
PAINT ORANGE (-1790 2435);
FORCEPROP 2 LASTPIN (-1800 2375) $PN 170
J 0
(-1790 2385);
DISPLAY 0.617021 (-1790 2385);
PAINT ORANGE (-1790 2385);
FORCEPROP 2 LASTPIN (-1800 2325) $PN 25
J 0
(-1790 2335);
DISPLAY 0.617021 (-1790 2335);
PAINT ORANGE (-1790 2335);
FORCEPROP 2 LASTPIN (-1800 2275) $PN 179
J 0
(-1790 2285);
DISPLAY 0.617021 (-1790 2285);
PAINT ORANGE (-1790 2285);
FORCEPROP 2 LASTPIN (-1800 2225) $PN 34
J 0
(-1790 2235);
DISPLAY 0.617021 (-1790 2235);
PAINT ORANGE (-1790 2235);
FORCEPROP 2 LASTPIN (-1800 2175) $PN 172
J 0
(-1790 2185);
DISPLAY 0.617021 (-1790 2185);
PAINT ORANGE (-1790 2185);
FORCEPROP 2 LASTPIN (-1800 2125) $PN 27
J 0
(-1790 2135);
DISPLAY 0.617021 (-1790 2135);
PAINT ORANGE (-1790 2135);
FORCEPROP 2 LASTPIN (-1800 2075) $PN 166
J 0
(-1790 2085);
DISPLAY 0.617021 (-1790 2085);
PAINT ORANGE (-1790 2085);
FORCEPROP 2 LASTPIN (-1800 2025) $PN 21
J 0
(-1790 2035);
DISPLAY 0.617021 (-1790 2035);
PAINT ORANGE (-1790 2035);
FORCEPROP 2 LASTPIN (-1800 1975) $PN 159
J 0
(-1790 1985);
DISPLAY 0.617021 (-1790 1985);
PAINT ORANGE (-1790 1985);
FORCEPROP 2 LASTPIN (-1800 1925) $PN 14
J 0
(-1790 1935);
DISPLAY 0.617021 (-1790 1935);
PAINT ORANGE (-1790 1935);
FORCEPROP 2 LASTPIN (-1800 1875) $PN 168
J 0
(-1790 1885);
DISPLAY 0.617021 (-1790 1885);
PAINT ORANGE (-1790 1885);
FORCEPROP 2 LASTPIN (-1800 1825) $PN 23
J 0
(-1790 1835);
DISPLAY 0.617021 (-1790 1835);
PAINT ORANGE (-1790 1835);
FORCEPROP 2 LASTPIN (-1800 1775) $PN 161
J 0
(-1790 1785);
DISPLAY 0.617021 (-1790 1785);
PAINT ORANGE (-1790 1785);
FORCEPROP 2 LASTPIN (-1800 1725) $PN 16
J 0
(-1790 1735);
DISPLAY 0.617021 (-1790 1735);
PAINT ORANGE (-1790 1735);
FORCEPROP 2 LASTPIN (-1800 1675) $PN 155
J 0
(-1790 1685);
DISPLAY 0.617021 (-1790 1685);
PAINT ORANGE (-1790 1685);
FORCEPROP 2 LASTPIN (-1800 1625) $PN 10
J 0
(-1790 1635);
DISPLAY 0.617021 (-1790 1635);
PAINT ORANGE (-1790 1635);
FORCEPROP 2 LASTPIN (-1800 1575) $PN 148
J 0
(-1790 1585);
DISPLAY 0.617021 (-1790 1585);
PAINT ORANGE (-1790 1585);
FORCEPROP 2 LASTPIN (-1800 1525) $PN 3
J 0
(-1790 1535);
DISPLAY 0.617021 (-1790 1535);
PAINT ORANGE (-1790 1535);
FORCEPROP 2 LASTPIN (-1800 1475) $PN 157
J 0
(-1790 1485);
DISPLAY 0.617021 (-1790 1485);
PAINT ORANGE (-1790 1485);
FORCEPROP 2 LASTPIN (-1800 1425) $PN 12
J 0
(-1790 1435);
DISPLAY 0.617021 (-1790 1435);
PAINT ORANGE (-1790 1435);
FORCEPROP 2 LASTPIN (-1800 1375) $PN 150
J 0
(-1790 1385);
DISPLAY 0.617021 (-1790 1385);
PAINT ORANGE (-1790 1385);
FORCEPROP 2 LASTPIN (-1800 1325) $PN 5
J 0
(-1790 1335);
DISPLAY 0.617021 (-1790 1335);
PAINT ORANGE (-1790 1335);
FORCEPROP 2 LASTPIN (-2800 2725) $PN 203
J 2
(-2810 2735);
DISPLAY 0.617021 (-2810 2735);
PAINT ORANGE (-2810 2735);
FORCEPROP 2 LASTPIN (-2800 2675) $PN 60
J 2
(-2810 2685);
DISPLAY 0.617021 (-2810 2685);
PAINT ORANGE (-2810 2685);
FORCEPROP 2 LASTPIN (-2800 3275) $PN 218
J 2
(-2810 3285);
DISPLAY 0.617021 (-2810 3285);
PAINT ORANGE (-2810 3285);
FORCEPROP 2 LASTPIN (-2800 3225) $PN 219
J 2
(-2810 3235);
DISPLAY 0.617021 (-2810 3235);
PAINT ORANGE (-2810 3235);
FORCEPROP 2 LASTPIN (-2800 3175) $PN 74
J 2
(-2810 3185);
DISPLAY 0.617021 (-2810 3185);
PAINT ORANGE (-2810 3185);
FORCEPROP 2 LASTPIN (-2800 3125) $PN 75
J 2
(-2810 3135);
DISPLAY 0.617021 (-2810 3135);
PAINT ORANGE (-2810 3135);
FORCEPROP 2 LASTPIN (-2800 2425) $PN 199
J 2
(-2810 2435);
DISPLAY 0.617021 (-2810 2435);
PAINT ORANGE (-2810 2435);
FORCEPROP 2 LASTPIN (-2800 2375) $PN 54
J 2
(-2810 2385);
DISPLAY 0.617021 (-2810 2385);
PAINT ORANGE (-2810 2385);
FORCEPROP 2 LASTPIN (-2800 2325) $PN 192
J 2
(-2810 2335);
DISPLAY 0.617021 (-2810 2335);
PAINT ORANGE (-2810 2335);
FORCEPROP 2 LASTPIN (-2800 2275) $PN 47
J 2
(-2810 2285);
DISPLAY 0.617021 (-2810 2285);
PAINT ORANGE (-2810 2285);
FORCEPROP 2 LASTPIN (-2800 2225) $PN 201
J 2
(-2810 2235);
DISPLAY 0.617021 (-2810 2235);
PAINT ORANGE (-2810 2235);
FORCEPROP 2 LASTPIN (-2800 2175) $PN 56
J 2
(-2810 2185);
DISPLAY 0.617021 (-2810 2185);
PAINT ORANGE (-2810 2185);
FORCEPROP 2 LASTPIN (-2800 2125) $PN 194
J 2
(-2810 2135);
DISPLAY 0.617021 (-2810 2135);
PAINT ORANGE (-2810 2135);
FORCEPROP 2 LASTPIN (-2800 2075) $PN 49
J 2
(-2810 2085);
DISPLAY 0.617021 (-2810 2085);
PAINT ORANGE (-2810 2085);
FORCEPROP 2 LASTPIN (-2800 3025) $PN 235
J 2
(-2810 3035);
DISPLAY 0.617021 (-2810 3035);
PAINT ORANGE (-2810 3035);
FORCEPROP 2 LASTPIN (-2800 3425) $PN 207
J 2
(-2810 3435);
DISPLAY 0.617021 (-2810 3435);
PAINT ORANGE (-2810 3435);
FORCEPROP 2 LASTPIN (-2800 3375) $PN 63
J 2
(-2810 3385);
DISPLAY 0.617021 (-2810 3385);
PAINT ORANGE (-2810 3385);
FORCEPROP 2 LASTPIN (-2800 3525) $PN 224
J 2
(-2810 3535);
DISPLAY 0.617021 (-2810 3535);
PAINT ORANGE (-2810 3535);
FORCEPROP 2 LASTPIN (-2800 3475) $PN 81
J 2
(-2810 3485);
DISPLAY 0.617021 (-2810 3485);
PAINT ORANGE (-2810 3485);
FORCEPROP 2 LASTPIN (-2800 1825) $PN 208
J 2
(-2810 1835);
DISPLAY 0.617021 (-2810 1835);
PAINT ORANGE (-2810 1835);
FORCEPROP 2 LASTPIN (-2800 1775) $PN 62
J 2
(-2810 1785);
DISPLAY 0.617021 (-2810 1785);
PAINT ORANGE (-2810 1785);
FORCEPROP 2 LASTPIN (-2800 4475) $PN 234
J 2
(-2810 4485);
DISPLAY 0.617021 (-2810 4485);
PAINT ORANGE (-2810 4485);
FORCEPROP 2 LASTPIN (-2800 4425) $PN 82
J 2
(-2810 4435);
DISPLAY 0.617021 (-2810 4435);
PAINT ORANGE (-2810 4435);
FORCEPROP 2 LASTPIN (-2800 4375) $PN 86
J 2
(-2810 4385);
DISPLAY 0.617021 (-2810 4385);
PAINT ORANGE (-2810 4385);
FORCEPROP 2 LASTPIN (-2800 4325) $PN 228
J 2
(-2810 4335);
DISPLAY 0.617021 (-2810 4335);
PAINT ORANGE (-2810 4335);
FORCEPROP 2 LASTPIN (-2800 4275) $PN 232
J 2
(-2810 4285);
DISPLAY 0.617021 (-2810 4285);
PAINT ORANGE (-2810 4285);
FORCEPROP 2 LASTPIN (-2800 4225) $PN 65
J 2
(-2810 4235);
DISPLAY 0.617021 (-2810 4235);
PAINT ORANGE (-2810 4235);
FORCEPROP 2 LASTPIN (-2800 4175) $PN 210
J 2
(-2810 4185);
DISPLAY 0.617021 (-2810 4185);
PAINT ORANGE (-2810 4185);
FORCEPROP 2 LASTPIN (-2800 4125) $PN 225
J 2
(-2810 4135);
DISPLAY 0.617021 (-2810 4135);
PAINT ORANGE (-2810 4135);
FORCEPROP 2 LASTPIN (-2800 4075) $PN 66
J 2
(-2810 4085);
DISPLAY 0.617021 (-2810 4085);
PAINT ORANGE (-2810 4085);
FORCEPROP 2 LASTPIN (-2800 3975) $PN 211
J 2
(-2810 3985);
DISPLAY 0.617021 (-2810 3985);
PAINT ORANGE (-2810 3985);
FORCEPROP 2 LASTPIN (-2800 3925) $PN 69
J 2
(-2810 3935);
DISPLAY 0.617021 (-2810 3935);
PAINT ORANGE (-2810 3935);
FORCEPROP 2 LASTPIN (-2800 3825) $PN 214
J 2
(-2810 3835);
DISPLAY 0.617021 (-2810 3835);
PAINT ORANGE (-2810 3835);
FORCEPROP 2 LASTPIN (-2800 3775) $PN 71
J 2
(-2810 3785);
DISPLAY 0.617021 (-2810 3785);
PAINT ORANGE (-2810 3785);
FORCEPROP 2 LASTPIN (-2800 3675) $PN 72
J 2
(-2810 3685);
DISPLAY 0.617021 (-2810 3685);
PAINT ORANGE (-2810 3685);
FORCEPROP 2 LASTPIN (-2800 3625) $PN 79
J 2
(-2810 3635);
DISPLAY 0.617021 (-2810 3635);
PAINT ORANGE (-2810 3635);
FORCEPROP 2 LASTPIN (-1800 3425) $PN 115
J 0
(-1790 3435);
DISPLAY 0.617021 (-1790 3435);
PAINT ORANGE (-1790 3435);
FORCEPROP 2 LASTPIN (-2800 4025) $PN 68
J 2
(-2810 4035);
DISPLAY 0.617021 (-2810 4035);
PAINT ORANGE (-2810 4035);
FORCEPROP 1 LAST MATERIAL SCONN
J 0
(-2750 4675);
DISPLAY 0.617021 (-2750 4675);
PAINT SKYBLUE (-2750 4675);
FORCEPROP 2 LASTPIN (-2800 3875) $PN 213
J 2
(-2810 3885);
DISPLAY 0.617021 (-2810 3885);
PAINT ORANGE (-2810 3885);
FORCEPROP 2 LASTPIN (-1800 4325) $PN 128
J 0
(-1790 4335);
DISPLAY 0.617021 (-1790 4335);
PAINT ORANGE (-1790 4335);
FORCEPROP 2 LASTPIN (-2800 3725) $PN 216
J 2
(-2810 3735);
DISPLAY 0.617021 (-2810 3735);
PAINT ORANGE (-2810 3735);
FORCEPROP 2 LASTPIN (-1800 4125) $PN 130
J 0
(-1790 4135);
DISPLAY 0.617021 (-1790 4135);
PAINT ORANGE (-1790 4135);
FORCEPROP 1 LAST LOCATION J4A1
J 0
(-2750 4725);
DISPLAY 0.617021 (-2750 4725);
PAINT AQUA (-2750 4725);
FORCEPROP 2 LASTPIN (-1800 3025) $PN 104
J 0
(-1790 3035);
DISPLAY 0.617021 (-1790 3035);
PAINT ORANGE (-1790 3035);
FORCEPROP 2 LASTPIN (-1800 2975) $PN 242
J 0
(-1790 2985);
DISPLAY 0.617021 (-1790 2985);
PAINT ORANGE (-1790 2985);
FORCEPROP 2 LASTPIN (-1800 2875) $PN 188
J 0
(-1790 2885);
DISPLAY 0.617021 (-1790 2885);
PAINT ORANGE (-1790 2885);
FORCEPROP 2 LASTPIN (-1800 2825) $PN 43
J 0
(-1790 2835);
DISPLAY 0.617021 (-1790 2835);
PAINT ORANGE (-1790 2835);
FORCEPROP 1 LAST PACK_TYPE PIP
J 0
(-2750 4775);
PAINT SKYBLUE (-2750 4775);
DISPLAY INVISIBLE (-2750 4775);
FORCEPROP 2 LAST BOM_COST MEM
J 0
(-2300 2830);
PAINT ORANGE (-2300 2830);
DISPLAY INVISIBLE (-2300 2830);
FORCEPROP 2 LAST CDS_LIB mstr_sconn
J 0
(-2300 2825);
PAINT ORANGE (-2300 2825);
DISPLAY INVISIBLE (-2300 2825);
FORCEPROP 2 LAST SEC_TYPE PIP
J 0
(-2750 4800);
DISPLAY 1.021277 (-2750 4800);
PAINT ORANGE (-2750 4800);
DISPLAY INVISIBLE (-2750 4800);
FORCEPROP 2 LAST SEC 1
J 0
(-2750 4800);
DISPLAY 0.680851 (-2750 4800);
PAINT MONO (-2750 4800);
DISPLAY INVISIBLE (-2750 4800);
FORCEPROP 2 LAST CDS_LOCATION J4A1
J 0
(-2750 4725);
DISPLAY 0.617021 (-2750 4725);
PAINT AQUA (-2750 4725);
DISPLAY INVISIBLE (-2750 4725);
FORCEPROP 1 LAST PATH I111
J 0
(-2300 4675);
PAINT GREEN (-2300 4675);
DISPLAY INVISIBLE (-2300 4675);
FORCEPROP 2 LAST ROOM DDR4_CH_F
J 0
(-2300 2830);
PAINT ORANGE (-2300 2830);
DISPLAY INVISIBLE (-2300 2830);
FORCEADD TAP..6
(-3050 4475);
FORCEPROP 3 LASTPIN (-3000 4475) SIG_NAME M_F_MA<17>
J 0
(-2990 4485);
DISPLAY 0.659574 (-2990 4485);
PAINT MONO (-2990 4485);
DISPLAY INVISIBLE (-2990 4485);
FORCEPROP 1 LASTPIN (-3000 4475) BN 17
J 0
(-3050 4485);
DISPLAY 0.617021 (-3050 4485);
PAINT PINK (-3050 4485);
FORCEPROP 2 LAST CDS_LIB mstr_standard
J 0
(-3050 4475);
DISPLAY 0.787234 (-3050 4475);
PAINT MONO (-3050 4475);
DISPLAY INVISIBLE (-3050 4475);
FORCEPROP 1 LAST BODY_TYPE PLUMBING
J 0
(-3050 4425);
DISPLAY 1.234043 (-3050 4425);
PAINT GREEN (-3050 4425);
DISPLAY INVISIBLE (-3050 4425);
FORCEPROP 1 LAST HDL_TAP TRUE
J 0
(-2725 4350);
DISPLAY 1.234043 (-2725 4350);
PAINT GREEN (-2725 4350);
DISPLAY INVISIBLE (-2725 4350);
FORCEPROP 1 LAST PATH I112
J 0
(-3050 4475);
DISPLAY 0.936170 (-3050 4475);
PAINT GREEN (-3050 4475);
DISPLAY INVISIBLE (-3050 4475);
FORCEADD TAP..6
(-3050 4425);
FORCEPROP 3 LASTPIN (-3000 4425) SIG_NAME M_F_MA<16>
J 0
(-2990 4435);
DISPLAY 0.659574 (-2990 4435);
PAINT MONO (-2990 4435);
DISPLAY INVISIBLE (-2990 4435);
FORCEPROP 1 LASTPIN (-3000 4425) BN 16
J 0
(-3050 4435);
DISPLAY 0.617021 (-3050 4435);
PAINT PINK (-3050 4435);
FORCEPROP 2 LAST CDS_LIB mstr_standard
J 2
(-3050 4425);
DISPLAY 0.787234 (-3050 4425);
PAINT MONO (-3050 4425);
DISPLAY INVISIBLE (-3050 4425);
FORCEPROP 1 LAST BODY_TYPE PLUMBING
J 0
(-3050 4375);
DISPLAY 1.234043 (-3050 4375);
PAINT GREEN (-3050 4375);
DISPLAY INVISIBLE (-3050 4375);
FORCEPROP 1 LAST HDL_TAP TRUE
J 0
(-2725 4300);
DISPLAY 1.234043 (-2725 4300);
PAINT GREEN (-2725 4300);
DISPLAY INVISIBLE (-2725 4300);
FORCEPROP 1 LAST PATH I113
J 0
(-3050 4425);
DISPLAY 0.936170 (-3050 4425);
PAINT GREEN (-3050 4425);
DISPLAY INVISIBLE (-3050 4425);
FORCEADD TAP..6
(-3050 4375);
FORCEPROP 3 LASTPIN (-3000 4375) SIG_NAME M_F_MA<15>
J 0
(-2990 4385);
DISPLAY 0.659574 (-2990 4385);
PAINT MONO (-2990 4385);
DISPLAY INVISIBLE (-2990 4385);
FORCEPROP 1 LASTPIN (-3000 4375) BN 15
J 0
(-3050 4385);
DISPLAY 0.617021 (-3050 4385);
PAINT PINK (-3050 4385);
FORCEPROP 2 LAST CDS_LIB mstr_standard
J 2
(-3050 4375);
DISPLAY 0.787234 (-3050 4375);
PAINT MONO (-3050 4375);
DISPLAY INVISIBLE (-3050 4375);
FORCEPROP 1 LAST BODY_TYPE PLUMBING
J 0
(-3050 4325);
DISPLAY 1.234043 (-3050 4325);
PAINT GREEN (-3050 4325);
DISPLAY INVISIBLE (-3050 4325);
FORCEPROP 1 LAST HDL_TAP TRUE
J 0
(-2725 4250);
DISPLAY 1.234043 (-2725 4250);
PAINT GREEN (-2725 4250);
DISPLAY INVISIBLE (-2725 4250);
FORCEPROP 1 LAST PATH I114
J 0
(-3050 4375);
DISPLAY 0.936170 (-3050 4375);
PAINT GREEN (-3050 4375);
DISPLAY INVISIBLE (-3050 4375);
FORCEADD TAP..6
(-3050 4325);
FORCEPROP 3 LASTPIN (-3000 4325) SIG_NAME M_F_MA<14>
J 0
(-2990 4335);
DISPLAY 0.659574 (-2990 4335);
PAINT MONO (-2990 4335);
DISPLAY INVISIBLE (-2990 4335);
FORCEPROP 1 LASTPIN (-3000 4325) BN 14
J 0
(-3050 4335);
DISPLAY 0.617021 (-3050 4335);
PAINT PINK (-3050 4335);
FORCEPROP 2 LAST CDS_LIB mstr_standard
J 2
(-3050 4325);
DISPLAY 0.787234 (-3050 4325);
PAINT MONO (-3050 4325);
DISPLAY INVISIBLE (-3050 4325);
FORCEPROP 1 LAST BODY_TYPE PLUMBING
J 0
(-3050 4275);
DISPLAY 1.234043 (-3050 4275);
PAINT GREEN (-3050 4275);
DISPLAY INVISIBLE (-3050 4275);
FORCEPROP 1 LAST HDL_TAP TRUE
J 0
(-2725 4200);
DISPLAY 1.234043 (-2725 4200);
PAINT GREEN (-2725 4200);
DISPLAY INVISIBLE (-2725 4200);
FORCEPROP 1 LAST PATH I115
J 0
(-3050 4325);
DISPLAY 0.936170 (-3050 4325);
PAINT GREEN (-3050 4325);
DISPLAY INVISIBLE (-3050 4325);
FORCEADD TAP..6
(-3050 4275);
FORCEPROP 3 LASTPIN (-3000 4275) SIG_NAME M_F_MA<13>
J 0
(-2990 4285);
DISPLAY 0.659574 (-2990 4285);
PAINT MONO (-2990 4285);
DISPLAY INVISIBLE (-2990 4285);
FORCEPROP 1 LASTPIN (-3000 4275) BN 13
J 0
(-3050 4285);
DISPLAY 0.617021 (-3050 4285);
PAINT PINK (-3050 4285);
FORCEPROP 2 LAST CDS_LIB mstr_standard
J 2
(-3050 4275);
DISPLAY 0.787234 (-3050 4275);
PAINT MONO (-3050 4275);
DISPLAY INVISIBLE (-3050 4275);
FORCEPROP 1 LAST BODY_TYPE PLUMBING
J 0
(-3050 4225);
DISPLAY 1.234043 (-3050 4225);
PAINT GREEN (-3050 4225);
DISPLAY INVISIBLE (-3050 4225);
FORCEPROP 1 LAST HDL_TAP TRUE
J 0
(-2725 4150);
DISPLAY 1.234043 (-2725 4150);
PAINT GREEN (-2725 4150);
DISPLAY INVISIBLE (-2725 4150);
FORCEPROP 1 LAST PATH I116
J 0
(-3050 4275);
DISPLAY 0.936170 (-3050 4275);
PAINT GREEN (-3050 4275);
DISPLAY INVISIBLE (-3050 4275);
FORCEADD TAP..6
(-3050 4225);
FORCEPROP 3 LASTPIN (-3000 4225) SIG_NAME M_F_MA<12>
J 0
(-2990 4235);
DISPLAY 0.659574 (-2990 4235);
PAINT MONO (-2990 4235);
DISPLAY INVISIBLE (-2990 4235);
FORCEPROP 1 LASTPIN (-3000 4225) BN 12
J 0
(-3050 4235);
DISPLAY 0.617021 (-3050 4235);
PAINT PINK (-3050 4235);
FORCEPROP 2 LAST CDS_LIB mstr_standard
J 2
(-3050 4225);
DISPLAY 0.787234 (-3050 4225);
PAINT MONO (-3050 4225);
DISPLAY INVISIBLE (-3050 4225);
FORCEPROP 1 LAST BODY_TYPE PLUMBING
J 0
(-3050 4175);
DISPLAY 1.234043 (-3050 4175);
PAINT GREEN (-3050 4175);
DISPLAY INVISIBLE (-3050 4175);
FORCEPROP 1 LAST HDL_TAP TRUE
J 0
(-2725 4100);
DISPLAY 1.234043 (-2725 4100);
PAINT GREEN (-2725 4100);
DISPLAY INVISIBLE (-2725 4100);
FORCEPROP 1 LAST PATH I117
J 0
(-3050 4225);
DISPLAY 0.936170 (-3050 4225);
PAINT GREEN (-3050 4225);
DISPLAY INVISIBLE (-3050 4225);
FORCEADD TAP..6
(-3050 4175);
FORCEPROP 3 LASTPIN (-3000 4175) SIG_NAME M_F_MA<11>
J 0
(-2990 4185);
DISPLAY 0.659574 (-2990 4185);
PAINT MONO (-2990 4185);
DISPLAY INVISIBLE (-2990 4185);
FORCEPROP 1 LASTPIN (-3000 4175) BN 11
J 0
(-3050 4185);
DISPLAY 0.617021 (-3050 4185);
PAINT PINK (-3050 4185);
FORCEPROP 2 LAST CDS_LIB mstr_standard
J 2
(-3050 4175);
DISPLAY 0.787234 (-3050 4175);
PAINT MONO (-3050 4175);
DISPLAY INVISIBLE (-3050 4175);
FORCEPROP 1 LAST BODY_TYPE PLUMBING
J 0
(-3050 4125);
DISPLAY 1.234043 (-3050 4125);
PAINT GREEN (-3050 4125);
DISPLAY INVISIBLE (-3050 4125);
FORCEPROP 1 LAST HDL_TAP TRUE
J 0
(-2725 4050);
DISPLAY 1.234043 (-2725 4050);
PAINT GREEN (-2725 4050);
DISPLAY INVISIBLE (-2725 4050);
FORCEPROP 1 LAST PATH I118
J 0
(-3050 4175);
DISPLAY 0.936170 (-3050 4175);
PAINT GREEN (-3050 4175);
DISPLAY INVISIBLE (-3050 4175);
FORCEADD TAP..6
(-3050 4125);
FORCEPROP 3 LASTPIN (-3000 4125) SIG_NAME M_F_MA<10>
J 0
(-2990 4135);
DISPLAY 0.659574 (-2990 4135);
PAINT MONO (-2990 4135);
DISPLAY INVISIBLE (-2990 4135);
FORCEPROP 1 LASTPIN (-3000 4125) BN 10
J 0
(-3050 4135);
DISPLAY 0.617021 (-3050 4135);
PAINT PINK (-3050 4135);
FORCEPROP 2 LAST CDS_LIB mstr_standard
J 2
(-3050 4125);
DISPLAY 0.787234 (-3050 4125);
PAINT MONO (-3050 4125);
DISPLAY INVISIBLE (-3050 4125);
FORCEPROP 1 LAST BODY_TYPE PLUMBING
J 0
(-3050 4075);
DISPLAY 1.234043 (-3050 4075);
PAINT GREEN (-3050 4075);
DISPLAY INVISIBLE (-3050 4075);
FORCEPROP 1 LAST HDL_TAP TRUE
J 0
(-2725 4000);
DISPLAY 1.234043 (-2725 4000);
PAINT GREEN (-2725 4000);
DISPLAY INVISIBLE (-2725 4000);
FORCEPROP 1 LAST PATH I119
J 0
(-3050 4125);
DISPLAY 0.936170 (-3050 4125);
PAINT GREEN (-3050 4125);
DISPLAY INVISIBLE (-3050 4125);
FORCEADD TAP..6
R 2
(650 4900);
FORCEPROP 3 LASTPIN (600 4900) SIG_NAME M_F_DQS_DP<14>
J 0
(610 4910);
DISPLAY 0.659574 (610 4910);
PAINT MONO (610 4910);
DISPLAY INVISIBLE (610 4910);
FORCEPROP 1 LASTPIN (600 4900) BN 14
J 2
(650 4910);
DISPLAY 0.617021 (650 4910);
PAINT PINK (650 4910);
FORCEPROP 2 LAST CDS_LIB mstr_standard
J 0
(650 4900);
DISPLAY 0.787234 (650 4900);
PAINT MONO (650 4900);
DISPLAY INVISIBLE (650 4900);
FORCEPROP 1 LAST BODY_TYPE PLUMBING
J 2
(650 4850);
DISPLAY 1.234043 (650 4850);
PAINT GREEN (650 4850);
DISPLAY INVISIBLE (650 4850);
FORCEPROP 1 LAST HDL_TAP TRUE
J 2
(325 4775);
DISPLAY 1.234043 (325 4775);
PAINT GREEN (325 4775);
DISPLAY INVISIBLE (325 4775);
FORCEPROP 1 LAST PATH I12
J 2
(650 4900);
DISPLAY 0.936170 (650 4900);
PAINT GREEN (650 4900);
DISPLAY INVISIBLE (650 4900);
FORCEADD TAP..6
(-3050 4075);
FORCEPROP 3 LASTPIN (-3000 4075) SIG_NAME M_F_MA<9>
J 0
(-2990 4085);
DISPLAY 0.659574 (-2990 4085);
PAINT MONO (-2990 4085);
DISPLAY INVISIBLE (-2990 4085);
FORCEPROP 1 LASTPIN (-3000 4075) BN 9
J 0
(-3050 4085);
DISPLAY 0.617021 (-3050 4085);
PAINT PINK (-3050 4085);
FORCEPROP 2 LAST CDS_LIB mstr_standard
J 2
(-3050 4075);
DISPLAY 0.787234 (-3050 4075);
PAINT MONO (-3050 4075);
DISPLAY INVISIBLE (-3050 4075);
FORCEPROP 1 LAST BODY_TYPE PLUMBING
J 0
(-3050 4025);
DISPLAY 1.234043 (-3050 4025);
PAINT GREEN (-3050 4025);
DISPLAY INVISIBLE (-3050 4025);
FORCEPROP 1 LAST HDL_TAP TRUE
J 0
(-2725 3950);
DISPLAY 1.234043 (-2725 3950);
PAINT GREEN (-2725 3950);
DISPLAY INVISIBLE (-2725 3950);
FORCEPROP 1 LAST PATH I120
J 0
(-3050 4075);
DISPLAY 0.936170 (-3050 4075);
PAINT GREEN (-3050 4075);
DISPLAY INVISIBLE (-3050 4075);
FORCEADD TAP..6
(-3050 4025);
FORCEPROP 3 LASTPIN (-3000 4025) SIG_NAME M_F_MA<8>
J 0
(-2990 4035);
DISPLAY 0.659574 (-2990 4035);
PAINT MONO (-2990 4035);
DISPLAY INVISIBLE (-2990 4035);
FORCEPROP 1 LASTPIN (-3000 4025) BN 8
J 0
(-3050 4035);
DISPLAY 0.617021 (-3050 4035);
PAINT PINK (-3050 4035);
FORCEPROP 2 LAST CDS_LIB mstr_standard
J 2
(-3050 4025);
DISPLAY 0.787234 (-3050 4025);
PAINT MONO (-3050 4025);
DISPLAY INVISIBLE (-3050 4025);
FORCEPROP 1 LAST BODY_TYPE PLUMBING
J 0
(-3050 3975);
DISPLAY 1.234043 (-3050 3975);
PAINT GREEN (-3050 3975);
DISPLAY INVISIBLE (-3050 3975);
FORCEPROP 1 LAST HDL_TAP TRUE
J 0
(-2725 3900);
DISPLAY 1.234043 (-2725 3900);
PAINT GREEN (-2725 3900);
DISPLAY INVISIBLE (-2725 3900);
FORCEPROP 1 LAST PATH I121
J 0
(-3050 4025);
DISPLAY 0.936170 (-3050 4025);
PAINT GREEN (-3050 4025);
DISPLAY INVISIBLE (-3050 4025);
FORCEADD TAP..6
(-3050 3975);
FORCEPROP 3 LASTPIN (-3000 3975) SIG_NAME M_F_MA<7>
J 0
(-2990 3985);
DISPLAY 0.659574 (-2990 3985);
PAINT MONO (-2990 3985);
DISPLAY INVISIBLE (-2990 3985);
FORCEPROP 1 LASTPIN (-3000 3975) BN 7
J 0
(-3050 3985);
DISPLAY 0.617021 (-3050 3985);
PAINT PINK (-3050 3985);
FORCEPROP 2 LAST CDS_LIB mstr_standard
J 2
(-3050 3975);
DISPLAY 0.787234 (-3050 3975);
PAINT MONO (-3050 3975);
DISPLAY INVISIBLE (-3050 3975);
FORCEPROP 1 LAST BODY_TYPE PLUMBING
J 0
(-3050 3925);
DISPLAY 1.234043 (-3050 3925);
PAINT GREEN (-3050 3925);
DISPLAY INVISIBLE (-3050 3925);
FORCEPROP 1 LAST HDL_TAP TRUE
J 0
(-2725 3850);
DISPLAY 1.234043 (-2725 3850);
PAINT GREEN (-2725 3850);
DISPLAY INVISIBLE (-2725 3850);
FORCEPROP 1 LAST PATH I122
J 0
(-3050 3975);
DISPLAY 0.936170 (-3050 3975);
PAINT GREEN (-3050 3975);
DISPLAY INVISIBLE (-3050 3975);
FORCEADD TAP..6
(-3050 3925);
FORCEPROP 3 LASTPIN (-3000 3925) SIG_NAME M_F_MA<6>
J 0
(-2990 3935);
DISPLAY 0.659574 (-2990 3935);
PAINT MONO (-2990 3935);
DISPLAY INVISIBLE (-2990 3935);
FORCEPROP 1 LASTPIN (-3000 3925) BN 6
J 0
(-3050 3935);
DISPLAY 0.617021 (-3050 3935);
PAINT PINK (-3050 3935);
FORCEPROP 2 LAST CDS_LIB mstr_standard
J 2
(-3050 3925);
DISPLAY 0.787234 (-3050 3925);
PAINT MONO (-3050 3925);
DISPLAY INVISIBLE (-3050 3925);
FORCEPROP 1 LAST BODY_TYPE PLUMBING
J 0
(-3050 3875);
DISPLAY 1.234043 (-3050 3875);
PAINT GREEN (-3050 3875);
DISPLAY INVISIBLE (-3050 3875);
FORCEPROP 1 LAST HDL_TAP TRUE
J 0
(-2725 3800);
DISPLAY 1.234043 (-2725 3800);
PAINT GREEN (-2725 3800);
DISPLAY INVISIBLE (-2725 3800);
FORCEPROP 1 LAST PATH I123
J 0
(-3050 3925);
DISPLAY 0.936170 (-3050 3925);
PAINT GREEN (-3050 3925);
DISPLAY INVISIBLE (-3050 3925);
FORCEADD TAP..6
(-3050 3875);
FORCEPROP 3 LASTPIN (-3000 3875) SIG_NAME M_F_MA<5>
J 0
(-2990 3885);
DISPLAY 0.659574 (-2990 3885);
PAINT MONO (-2990 3885);
DISPLAY INVISIBLE (-2990 3885);
FORCEPROP 1 LASTPIN (-3000 3875) BN 5
J 0
(-3050 3885);
DISPLAY 0.617021 (-3050 3885);
PAINT PINK (-3050 3885);
FORCEPROP 2 LAST CDS_LIB mstr_standard
J 2
(-3050 3875);
DISPLAY 0.787234 (-3050 3875);
PAINT MONO (-3050 3875);
DISPLAY INVISIBLE (-3050 3875);
FORCEPROP 1 LAST BODY_TYPE PLUMBING
J 0
(-3050 3825);
DISPLAY 1.234043 (-3050 3825);
PAINT GREEN (-3050 3825);
DISPLAY INVISIBLE (-3050 3825);
FORCEPROP 1 LAST HDL_TAP TRUE
J 0
(-2725 3750);
DISPLAY 1.234043 (-2725 3750);
PAINT GREEN (-2725 3750);
DISPLAY INVISIBLE (-2725 3750);
FORCEPROP 1 LAST PATH I124
J 0
(-3050 3875);
DISPLAY 0.936170 (-3050 3875);
PAINT GREEN (-3050 3875);
DISPLAY INVISIBLE (-3050 3875);
FORCEADD TAP..6
(-3050 3825);
FORCEPROP 3 LASTPIN (-3000 3825) SIG_NAME M_F_MA<4>
J 0
(-2990 3835);
DISPLAY 0.659574 (-2990 3835);
PAINT MONO (-2990 3835);
DISPLAY INVISIBLE (-2990 3835);
FORCEPROP 1 LASTPIN (-3000 3825) BN 4
J 0
(-3050 3835);
DISPLAY 0.617021 (-3050 3835);
PAINT PINK (-3050 3835);
FORCEPROP 2 LAST CDS_LIB mstr_standard
J 2
(-3050 3825);
DISPLAY 0.787234 (-3050 3825);
PAINT MONO (-3050 3825);
DISPLAY INVISIBLE (-3050 3825);
FORCEPROP 1 LAST BODY_TYPE PLUMBING
J 0
(-3050 3775);
DISPLAY 1.234043 (-3050 3775);
PAINT GREEN (-3050 3775);
DISPLAY INVISIBLE (-3050 3775);
FORCEPROP 1 LAST HDL_TAP TRUE
J 0
(-2725 3700);
DISPLAY 1.234043 (-2725 3700);
PAINT GREEN (-2725 3700);
DISPLAY INVISIBLE (-2725 3700);
FORCEPROP 1 LAST PATH I125
J 0
(-3050 3825);
DISPLAY 0.936170 (-3050 3825);
PAINT GREEN (-3050 3825);
DISPLAY INVISIBLE (-3050 3825);
FORCEADD TAP..6
(-3050 3775);
FORCEPROP 3 LASTPIN (-3000 3775) SIG_NAME M_F_MA<3>
J 0
(-2990 3785);
DISPLAY 0.659574 (-2990 3785);
PAINT MONO (-2990 3785);
DISPLAY INVISIBLE (-2990 3785);
FORCEPROP 1 LASTPIN (-3000 3775) BN 3
J 0
(-3050 3785);
DISPLAY 0.617021 (-3050 3785);
PAINT PINK (-3050 3785);
FORCEPROP 2 LAST CDS_LIB mstr_standard
J 2
(-3050 3775);
DISPLAY 0.787234 (-3050 3775);
PAINT MONO (-3050 3775);
DISPLAY INVISIBLE (-3050 3775);
FORCEPROP 1 LAST BODY_TYPE PLUMBING
J 0
(-3050 3725);
DISPLAY 1.234043 (-3050 3725);
PAINT GREEN (-3050 3725);
DISPLAY INVISIBLE (-3050 3725);
FORCEPROP 1 LAST HDL_TAP TRUE
J 0
(-2725 3650);
DISPLAY 1.234043 (-2725 3650);
PAINT GREEN (-2725 3650);
DISPLAY INVISIBLE (-2725 3650);
FORCEPROP 1 LAST PATH I126
J 0
(-3050 3775);
DISPLAY 0.936170 (-3050 3775);
PAINT GREEN (-3050 3775);
DISPLAY INVISIBLE (-3050 3775);
FORCEADD TAP..6
(-3050 3725);
FORCEPROP 3 LASTPIN (-3000 3725) SIG_NAME M_F_MA<2>
J 0
(-2990 3735);
DISPLAY 0.659574 (-2990 3735);
PAINT MONO (-2990 3735);
DISPLAY INVISIBLE (-2990 3735);
FORCEPROP 1 LASTPIN (-3000 3725) BN 2
J 0
(-3050 3735);
DISPLAY 0.617021 (-3050 3735);
PAINT PINK (-3050 3735);
FORCEPROP 2 LAST CDS_LIB mstr_standard
J 2
(-3050 3725);
DISPLAY 0.787234 (-3050 3725);
PAINT MONO (-3050 3725);
DISPLAY INVISIBLE (-3050 3725);
FORCEPROP 1 LAST BODY_TYPE PLUMBING
J 0
(-3050 3675);
DISPLAY 1.234043 (-3050 3675);
PAINT GREEN (-3050 3675);
DISPLAY INVISIBLE (-3050 3675);
FORCEPROP 1 LAST HDL_TAP TRUE
J 0
(-2725 3600);
DISPLAY 1.234043 (-2725 3600);
PAINT GREEN (-2725 3600);
DISPLAY INVISIBLE (-2725 3600);
FORCEPROP 1 LAST PATH I127
J 0
(-3050 3725);
DISPLAY 0.936170 (-3050 3725);
PAINT GREEN (-3050 3725);
DISPLAY INVISIBLE (-3050 3725);
FORCEADD TAP..6
(-3050 3675);
FORCEPROP 3 LASTPIN (-3000 3675) SIG_NAME M_F_MA<1>
J 0
(-2990 3685);
DISPLAY 0.659574 (-2990 3685);
PAINT MONO (-2990 3685);
DISPLAY INVISIBLE (-2990 3685);
FORCEPROP 1 LASTPIN (-3000 3675) BN 1
J 0
(-3050 3685);
DISPLAY 0.617021 (-3050 3685);
PAINT PINK (-3050 3685);
FORCEPROP 2 LAST CDS_LIB mstr_standard
J 2
(-3050 3675);
DISPLAY 0.787234 (-3050 3675);
PAINT MONO (-3050 3675);
DISPLAY INVISIBLE (-3050 3675);
FORCEPROP 1 LAST BODY_TYPE PLUMBING
J 0
(-3050 3625);
DISPLAY 1.234043 (-3050 3625);
PAINT GREEN (-3050 3625);
DISPLAY INVISIBLE (-3050 3625);
FORCEPROP 1 LAST HDL_TAP TRUE
J 0
(-2725 3550);
DISPLAY 1.234043 (-2725 3550);
PAINT GREEN (-2725 3550);
DISPLAY INVISIBLE (-2725 3550);
FORCEPROP 1 LAST PATH I128
J 0
(-3050 3675);
DISPLAY 0.936170 (-3050 3675);
PAINT GREEN (-3050 3675);
DISPLAY INVISIBLE (-3050 3675);
FORCEADD TAP..6
(-3050 3625);
FORCEPROP 3 LASTPIN (-3000 3625) SIG_NAME M_F_MA<0>
J 0
(-2990 3635);
DISPLAY 0.659574 (-2990 3635);
PAINT MONO (-2990 3635);
DISPLAY INVISIBLE (-2990 3635);
FORCEPROP 1 LASTPIN (-3000 3625) BN 0
J 0
(-3050 3635);
DISPLAY 0.617021 (-3050 3635);
PAINT PINK (-3050 3635);
FORCEPROP 2 LAST CDS_LIB mstr_standard
J 2
(-3050 3625);
DISPLAY 0.787234 (-3050 3625);
PAINT MONO (-3050 3625);
DISPLAY INVISIBLE (-3050 3625);
FORCEPROP 1 LAST BODY_TYPE PLUMBING
J 0
(-3050 3575);
DISPLAY 1.234043 (-3050 3575);
PAINT GREEN (-3050 3575);
DISPLAY INVISIBLE (-3050 3575);
FORCEPROP 1 LAST HDL_TAP TRUE
J 0
(-2725 3500);
DISPLAY 1.234043 (-2725 3500);
PAINT GREEN (-2725 3500);
DISPLAY INVISIBLE (-2725 3500);
FORCEPROP 1 LAST PATH I129
J 0
(-3050 3625);
DISPLAY 0.936170 (-3050 3625);
PAINT GREEN (-3050 3625);
DISPLAY INVISIBLE (-3050 3625);
FORCEADD TAP..6
R 2
(650 4800);
FORCEPROP 3 LASTPIN (600 4800) SIG_NAME M_F_DQS_DP<13>
J 0
(610 4810);
DISPLAY 0.659574 (610 4810);
PAINT MONO (610 4810);
DISPLAY INVISIBLE (610 4810);
FORCEPROP 1 LASTPIN (600 4800) BN 13
J 2
(650 4810);
DISPLAY 0.617021 (650 4810);
PAINT PINK (650 4810);
FORCEPROP 2 LAST CDS_LIB mstr_standard
J 0
(650 4800);
DISPLAY 0.787234 (650 4800);
PAINT MONO (650 4800);
DISPLAY INVISIBLE (650 4800);
FORCEPROP 1 LAST BODY_TYPE PLUMBING
J 2
(650 4750);
DISPLAY 1.234043 (650 4750);
PAINT GREEN (650 4750);
DISPLAY INVISIBLE (650 4750);
FORCEPROP 1 LAST HDL_TAP TRUE
J 2
(325 4675);
DISPLAY 1.234043 (325 4675);
PAINT GREEN (325 4675);
DISPLAY INVISIBLE (325 4675);
FORCEPROP 1 LAST PATH I13
J 2
(650 4800);
DISPLAY 0.936170 (650 4800);
PAINT GREEN (650 4800);
DISPLAY INVISIBLE (650 4800);
FORCEADD TAP..6
(-3050 3525);
FORCEPROP 3 LASTPIN (-3000 3525) SIG_NAME M_F_BA<1>
J 0
(-2990 3535);
DISPLAY 0.659574 (-2990 3535);
PAINT MONO (-2990 3535);
DISPLAY INVISIBLE (-2990 3535);
FORCEPROP 1 LASTPIN (-3000 3525) BN 1
J 0
(-3050 3535);
DISPLAY 0.617021 (-3050 3535);
PAINT PINK (-3050 3535);
FORCEPROP 2 LAST CDS_LIB mstr_standard
J 0
(-3050 3525);
DISPLAY 0.787234 (-3050 3525);
PAINT MONO (-3050 3525);
DISPLAY INVISIBLE (-3050 3525);
FORCEPROP 1 LAST BODY_TYPE PLUMBING
J 0
(-3050 3475);
DISPLAY 1.234043 (-3050 3475);
PAINT GREEN (-3050 3475);
DISPLAY INVISIBLE (-3050 3475);
FORCEPROP 1 LAST HDL_TAP TRUE
J 0
(-2725 3400);
DISPLAY 1.234043 (-2725 3400);
PAINT GREEN (-2725 3400);
DISPLAY INVISIBLE (-2725 3400);
FORCEPROP 1 LAST PATH I130
J 0
(-3050 3525);
DISPLAY 0.936170 (-3050 3525);
PAINT GREEN (-3050 3525);
DISPLAY INVISIBLE (-3050 3525);
FORCEADD OFFPAGE..1
(-3700 4525);
FORCEPROP 2 LAST $XR1 54 
J 0
(-4011 4525);
DISPLAY 0.638298 (-4011 4525);
PAINT MONO (-4011 4525);
FORCEPROP 2 LAST $XR0 28 
J 0
(-3921 4525);
DISPLAY 0.638298 (-3921 4525);
PAINT MONO (-3921 4525);
FORCEPROP 2 LAST CDS_LIB mstr_standard
J 0
(-3700 4525);
DISPLAY 0.787234 (-3700 4525);
PAINT MONO (-3700 4525);
DISPLAY INVISIBLE (-3700 4525);
FORCEPROP 1 LAST OFFPAGE TRUE
J 0
(-3375 4400);
DISPLAY 0.936170 (-3375 4400);
PAINT GREEN (-3375 4400);
DISPLAY INVISIBLE (-3375 4400);
FORCEPROP 1 LAST COMMENT_BODY TRUE
J 0
(-3575 4425);
DISPLAY 0.936170 (-3575 4425);
PAINT GREEN (-3575 4425);
DISPLAY INVISIBLE (-3575 4425);
FORCEPROP 2 LAST PATH I131
J 0
(-3650 4600);
DISPLAY 0.787234 (-3650 4600);
PAINT MONO (-3650 4600);
DISPLAY INVISIBLE (-3650 4600);
FORCEADD OFFPAGE..1
(-3700 3575);
FORCEPROP 2 LAST $XR1 54 
J 0
(-4011 3575);
DISPLAY 0.638298 (-4011 3575);
PAINT MONO (-4011 3575);
FORCEPROP 2 LAST $XR0 28 
J 0
(-3921 3575);
DISPLAY 0.638298 (-3921 3575);
PAINT MONO (-3921 3575);
FORCEPROP 2 LAST CDS_LIB mstr_standard
J 0
(-3700 3575);
DISPLAY 0.787234 (-3700 3575);
PAINT MONO (-3700 3575);
DISPLAY INVISIBLE (-3700 3575);
FORCEPROP 1 LAST OFFPAGE TRUE
J 0
(-3375 3450);
DISPLAY 0.936170 (-3375 3450);
PAINT GREEN (-3375 3450);
DISPLAY INVISIBLE (-3375 3450);
FORCEPROP 1 LAST COMMENT_BODY TRUE
J 0
(-3575 3475);
DISPLAY 0.936170 (-3575 3475);
PAINT GREEN (-3575 3475);
DISPLAY INVISIBLE (-3575 3475);
FORCEPROP 2 LAST PATH I132
J 0
(-3650 3650);
DISPLAY 0.787234 (-3650 3650);
PAINT MONO (-3650 3650);
DISPLAY INVISIBLE (-3650 3650);
FORCEADD TAP..6
(-3050 3475);
FORCEPROP 3 LASTPIN (-3000 3475) SIG_NAME M_F_BA<0>
J 0
(-2990 3485);
DISPLAY 0.659574 (-2990 3485);
PAINT MONO (-2990 3485);
DISPLAY INVISIBLE (-2990 3485);
FORCEPROP 1 LASTPIN (-3000 3475) BN 0
J 0
(-3050 3485);
DISPLAY 0.617021 (-3050 3485);
PAINT PINK (-3050 3485);
FORCEPROP 2 LAST CDS_LIB mstr_standard
J 0
(-3050 3475);
DISPLAY 0.787234 (-3050 3475);
PAINT MONO (-3050 3475);
DISPLAY INVISIBLE (-3050 3475);
FORCEPROP 1 LAST BODY_TYPE PLUMBING
J 0
(-3050 3425);
DISPLAY 1.234043 (-3050 3425);
PAINT GREEN (-3050 3425);
DISPLAY INVISIBLE (-3050 3425);
FORCEPROP 1 LAST HDL_TAP TRUE
J 0
(-2725 3350);
DISPLAY 1.234043 (-2725 3350);
PAINT GREEN (-2725 3350);
DISPLAY INVISIBLE (-2725 3350);
FORCEPROP 1 LAST PATH I133
J 0
(-3050 3475);
DISPLAY 0.936170 (-3050 3475);
PAINT GREEN (-3050 3475);
DISPLAY INVISIBLE (-3050 3475);
FORCEADD TAP..6
(-3050 3425);
FORCEPROP 3 LASTPIN (-3000 3425) SIG_NAME M_F_BG<1>
J 0
(-2990 3435);
DISPLAY 0.659574 (-2990 3435);
PAINT MONO (-2990 3435);
DISPLAY INVISIBLE (-2990 3435);
FORCEPROP 1 LASTPIN (-3000 3425) BN 1
J 0
(-3050 3435);
DISPLAY 0.617021 (-3050 3435);
PAINT PINK (-3050 3435);
FORCEPROP 2 LAST CDS_LIB mstr_standard
J 0
(-3050 3425);
DISPLAY 0.787234 (-3050 3425);
PAINT MONO (-3050 3425);
DISPLAY INVISIBLE (-3050 3425);
FORCEPROP 1 LAST BODY_TYPE PLUMBING
J 0
(-3050 3375);
DISPLAY 1.234043 (-3050 3375);
PAINT GREEN (-3050 3375);
DISPLAY INVISIBLE (-3050 3375);
FORCEPROP 1 LAST HDL_TAP TRUE
J 0
(-2725 3300);
DISPLAY 1.234043 (-2725 3300);
PAINT GREEN (-2725 3300);
DISPLAY INVISIBLE (-2725 3300);
FORCEPROP 1 LAST PATH I134
J 0
(-3050 3425);
DISPLAY 0.936170 (-3050 3425);
PAINT GREEN (-3050 3425);
DISPLAY INVISIBLE (-3050 3425);
FORCEADD TAP..6
(-3050 3375);
FORCEPROP 3 LASTPIN (-3000 3375) SIG_NAME M_F_BG<0>
J 0
(-2990 3385);
DISPLAY 0.659574 (-2990 3385);
PAINT MONO (-2990 3385);
DISPLAY INVISIBLE (-2990 3385);
FORCEPROP 1 LASTPIN (-3000 3375) BN 0
J 0
(-3050 3385);
DISPLAY 0.617021 (-3050 3385);
PAINT PINK (-3050 3385);
FORCEPROP 2 LAST CDS_LIB mstr_standard
J 0
(-3050 3375);
DISPLAY 0.787234 (-3050 3375);
PAINT MONO (-3050 3375);
DISPLAY INVISIBLE (-3050 3375);
FORCEPROP 1 LAST BODY_TYPE PLUMBING
J 0
(-3050 3325);
DISPLAY 1.234043 (-3050 3325);
PAINT GREEN (-3050 3325);
DISPLAY INVISIBLE (-3050 3325);
FORCEPROP 1 LAST HDL_TAP TRUE
J 0
(-2725 3250);
DISPLAY 1.234043 (-2725 3250);
PAINT GREEN (-2725 3250);
DISPLAY INVISIBLE (-2725 3250);
FORCEPROP 1 LAST PATH I135
J 0
(-3050 3375);
DISPLAY 0.936170 (-3050 3375);
PAINT GREEN (-3050 3375);
DISPLAY INVISIBLE (-3050 3375);
FORCEADD OFFPAGE..1
(-3700 3075);
FORCEPROP 2 LAST $XR1 54 
J 0
(-4011 3075);
DISPLAY 0.638298 (-4011 3075);
PAINT MONO (-4011 3075);
FORCEPROP 2 LAST $XR0 28 
J 0
(-3921 3075);
DISPLAY 0.638298 (-3921 3075);
PAINT MONO (-3921 3075);
FORCEPROP 2 LAST CDS_LIB mstr_standard
J 0
(-3700 3075);
DISPLAY 0.787234 (-3700 3075);
PAINT MONO (-3700 3075);
DISPLAY INVISIBLE (-3700 3075);
FORCEPROP 1 LAST OFFPAGE TRUE
J 0
(-3375 2950);
DISPLAY 0.936170 (-3375 2950);
PAINT GREEN (-3375 2950);
DISPLAY INVISIBLE (-3375 2950);
FORCEPROP 1 LAST COMMENT_BODY TRUE
J 0
(-3575 2975);
DISPLAY 0.936170 (-3575 2975);
PAINT GREEN (-3575 2975);
DISPLAY INVISIBLE (-3575 2975);
FORCEPROP 2 LAST PATH I136
J 0
(-3650 3150);
DISPLAY 0.787234 (-3650 3150);
PAINT MONO (-3650 3150);
DISPLAY INVISIBLE (-3650 3150);
FORCEADD OFFPAGE..1
(-3700 3450);
FORCEPROP 2 LAST $XR1 54 
J 0
(-4011 3450);
DISPLAY 0.638298 (-4011 3450);
PAINT MONO (-4011 3450);
FORCEPROP 2 LAST $XR0 28 
J 0
(-3921 3450);
DISPLAY 0.638298 (-3921 3450);
PAINT MONO (-3921 3450);
FORCEPROP 2 LAST CDS_LIB mstr_standard
J 0
(-3700 3450);
DISPLAY 0.787234 (-3700 3450);
PAINT MONO (-3700 3450);
DISPLAY INVISIBLE (-3700 3450);
FORCEPROP 1 LAST OFFPAGE TRUE
J 0
(-3375 3325);
DISPLAY 0.936170 (-3375 3325);
PAINT GREEN (-3375 3325);
DISPLAY INVISIBLE (-3375 3325);
FORCEPROP 1 LAST COMMENT_BODY TRUE
J 0
(-3575 3350);
DISPLAY 0.936170 (-3575 3350);
PAINT GREEN (-3575 3350);
DISPLAY INVISIBLE (-3575 3350);
FORCEPROP 2 LAST PATH I137
J 0
(-3650 3525);
DISPLAY 0.787234 (-3650 3525);
PAINT MONO (-3650 3525);
DISPLAY INVISIBLE (-3650 3525);
FORCEADD TAP..6
(-3050 2375);
FORCEPROP 3 LASTPIN (-3000 2375) SIG_NAME M_F_ECC<7>
J 0
(-2990 2385);
DISPLAY 0.659574 (-2990 2385);
PAINT MONO (-2990 2385);
DISPLAY INVISIBLE (-2990 2385);
FORCEPROP 1 LASTPIN (-3000 2375) BN 7
J 0
(-3050 2385);
DISPLAY 0.617021 (-3050 2385);
PAINT PINK (-3050 2385);
FORCEPROP 2 LAST CDS_LIB mstr_standard
J 0
(-3050 2375);
DISPLAY 0.787234 (-3050 2375);
PAINT MONO (-3050 2375);
DISPLAY INVISIBLE (-3050 2375);
FORCEPROP 1 LAST BODY_TYPE PLUMBING
J 0
(-3050 2325);
DISPLAY 1.234043 (-3050 2325);
PAINT GREEN (-3050 2325);
DISPLAY INVISIBLE (-3050 2325);
FORCEPROP 1 LAST HDL_TAP TRUE
J 0
(-2725 2250);
DISPLAY 1.234043 (-2725 2250);
PAINT GREEN (-2725 2250);
DISPLAY INVISIBLE (-2725 2250);
FORCEPROP 1 LAST PATH I138
J 0
(-3050 2375);
DISPLAY 0.936170 (-3050 2375);
PAINT GREEN (-3050 2375);
DISPLAY INVISIBLE (-3050 2375);
FORCEADD TAP..6
(-3050 2425);
FORCEPROP 3 LASTPIN (-3000 2425) SIG_NAME M_F_ECC<6>
J 0
(-2990 2435);
DISPLAY 0.659574 (-2990 2435);
PAINT MONO (-2990 2435);
DISPLAY INVISIBLE (-2990 2435);
FORCEPROP 1 LASTPIN (-3000 2425) BN 6
J 0
(-3050 2435);
DISPLAY 0.617021 (-3050 2435);
PAINT PINK (-3050 2435);
FORCEPROP 2 LAST CDS_LIB mstr_standard
J 0
(-3050 2425);
DISPLAY 0.787234 (-3050 2425);
PAINT MONO (-3050 2425);
DISPLAY INVISIBLE (-3050 2425);
FORCEPROP 1 LAST BODY_TYPE PLUMBING
J 0
(-3050 2375);
DISPLAY 1.234043 (-3050 2375);
PAINT GREEN (-3050 2375);
DISPLAY INVISIBLE (-3050 2375);
FORCEPROP 1 LAST HDL_TAP TRUE
J 0
(-2725 2300);
DISPLAY 1.234043 (-2725 2300);
PAINT GREEN (-2725 2300);
DISPLAY INVISIBLE (-2725 2300);
FORCEPROP 1 LAST PATH I139
J 0
(-3050 2425);
DISPLAY 0.936170 (-3050 2425);
PAINT GREEN (-3050 2425);
DISPLAY INVISIBLE (-3050 2425);
FORCEADD TAP..6
R 2
(650 4600);
FORCEPROP 3 LASTPIN (600 4600) SIG_NAME M_F_DQS_DP<11>
J 0
(610 4610);
DISPLAY 0.659574 (610 4610);
PAINT MONO (610 4610);
DISPLAY INVISIBLE (610 4610);
FORCEPROP 1 LASTPIN (600 4600) BN 11
J 2
(650 4610);
DISPLAY 0.617021 (650 4610);
PAINT PINK (650 4610);
FORCEPROP 2 LAST CDS_LIB mstr_standard
J 0
(650 4600);
DISPLAY 0.787234 (650 4600);
PAINT MONO (650 4600);
DISPLAY INVISIBLE (650 4600);
FORCEPROP 1 LAST BODY_TYPE PLUMBING
J 2
(650 4550);
DISPLAY 1.234043 (650 4550);
PAINT GREEN (650 4550);
DISPLAY INVISIBLE (650 4550);
FORCEPROP 1 LAST HDL_TAP TRUE
J 2
(325 4475);
DISPLAY 1.234043 (325 4475);
PAINT GREEN (325 4475);
DISPLAY INVISIBLE (325 4475);
FORCEPROP 1 LAST PATH I14
J 2
(650 4600);
DISPLAY 0.936170 (650 4600);
PAINT GREEN (650 4600);
DISPLAY INVISIBLE (650 4600);
FORCEADD TAP..6
(-3050 2325);
FORCEPROP 3 LASTPIN (-3000 2325) SIG_NAME M_F_ECC<4>
J 0
(-2990 2335);
DISPLAY 0.659574 (-2990 2335);
PAINT MONO (-2990 2335);
DISPLAY INVISIBLE (-2990 2335);
FORCEPROP 1 LASTPIN (-3000 2325) BN 4
J 0
(-3050 2335);
DISPLAY 0.617021 (-3050 2335);
PAINT PINK (-3050 2335);
FORCEPROP 2 LAST CDS_LIB mstr_standard
J 0
(-3050 2325);
DISPLAY 0.787234 (-3050 2325);
PAINT MONO (-3050 2325);
DISPLAY INVISIBLE (-3050 2325);
FORCEPROP 1 LAST BODY_TYPE PLUMBING
J 0
(-3050 2275);
DISPLAY 1.234043 (-3050 2275);
PAINT GREEN (-3050 2275);
DISPLAY INVISIBLE (-3050 2275);
FORCEPROP 1 LAST HDL_TAP TRUE
J 0
(-2725 2200);
DISPLAY 1.234043 (-2725 2200);
PAINT GREEN (-2725 2200);
DISPLAY INVISIBLE (-2725 2200);
FORCEPROP 1 LAST PATH I140
J 0
(-3050 2325);
DISPLAY 0.936170 (-3050 2325);
PAINT GREEN (-3050 2325);
DISPLAY INVISIBLE (-3050 2325);
FORCEADD TAP..6
(-3050 2275);
FORCEPROP 3 LASTPIN (-3000 2275) SIG_NAME M_F_ECC<5>
J 0
(-2990 2285);
DISPLAY 0.659574 (-2990 2285);
PAINT MONO (-2990 2285);
DISPLAY INVISIBLE (-2990 2285);
FORCEPROP 1 LASTPIN (-3000 2275) BN 5
J 0
(-3050 2285);
DISPLAY 0.617021 (-3050 2285);
PAINT PINK (-3050 2285);
FORCEPROP 2 LAST CDS_LIB mstr_standard
J 0
(-3050 2275);
DISPLAY 0.787234 (-3050 2275);
PAINT MONO (-3050 2275);
DISPLAY INVISIBLE (-3050 2275);
FORCEPROP 1 LAST BODY_TYPE PLUMBING
J 0
(-3050 2225);
DISPLAY 1.234043 (-3050 2225);
PAINT GREEN (-3050 2225);
DISPLAY INVISIBLE (-3050 2225);
FORCEPROP 1 LAST HDL_TAP TRUE
J 0
(-2725 2150);
DISPLAY 1.234043 (-2725 2150);
PAINT GREEN (-2725 2150);
DISPLAY INVISIBLE (-2725 2150);
FORCEPROP 1 LAST PATH I141
J 0
(-3050 2275);
DISPLAY 0.936170 (-3050 2275);
PAINT GREEN (-3050 2275);
DISPLAY INVISIBLE (-3050 2275);
FORCEADD TAP..6
(-3050 2225);
FORCEPROP 3 LASTPIN (-3000 2225) SIG_NAME M_F_ECC<2>
J 0
(-2990 2235);
DISPLAY 0.659574 (-2990 2235);
PAINT MONO (-2990 2235);
DISPLAY INVISIBLE (-2990 2235);
FORCEPROP 1 LASTPIN (-3000 2225) BN 2
J 0
(-3050 2235);
DISPLAY 0.617021 (-3050 2235);
PAINT PINK (-3050 2235);
FORCEPROP 2 LAST CDS_LIB mstr_standard
J 0
(-3050 2225);
DISPLAY 0.787234 (-3050 2225);
PAINT MONO (-3050 2225);
DISPLAY INVISIBLE (-3050 2225);
FORCEPROP 1 LAST BODY_TYPE PLUMBING
J 0
(-3050 2175);
DISPLAY 1.234043 (-3050 2175);
PAINT GREEN (-3050 2175);
DISPLAY INVISIBLE (-3050 2175);
FORCEPROP 1 LAST HDL_TAP TRUE
J 0
(-2725 2100);
DISPLAY 1.234043 (-2725 2100);
PAINT GREEN (-2725 2100);
DISPLAY INVISIBLE (-2725 2100);
FORCEPROP 1 LAST PATH I142
J 0
(-3050 2225);
DISPLAY 0.936170 (-3050 2225);
PAINT GREEN (-3050 2225);
DISPLAY INVISIBLE (-3050 2225);
FORCEADD TAP..6
(-3050 2175);
FORCEPROP 3 LASTPIN (-3000 2175) SIG_NAME M_F_ECC<3>
J 0
(-2990 2185);
DISPLAY 0.659574 (-2990 2185);
PAINT MONO (-2990 2185);
DISPLAY INVISIBLE (-2990 2185);
FORCEPROP 1 LASTPIN (-3000 2175) BN 3
J 0
(-3050 2185);
DISPLAY 0.617021 (-3050 2185);
PAINT PINK (-3050 2185);
FORCEPROP 2 LAST CDS_LIB mstr_standard
J 0
(-3050 2175);
DISPLAY 0.787234 (-3050 2175);
PAINT MONO (-3050 2175);
DISPLAY INVISIBLE (-3050 2175);
FORCEPROP 1 LAST BODY_TYPE PLUMBING
J 0
(-3050 2125);
DISPLAY 1.234043 (-3050 2125);
PAINT GREEN (-3050 2125);
DISPLAY INVISIBLE (-3050 2125);
FORCEPROP 1 LAST HDL_TAP TRUE
J 0
(-2725 2050);
DISPLAY 1.234043 (-2725 2050);
PAINT GREEN (-2725 2050);
DISPLAY INVISIBLE (-2725 2050);
FORCEPROP 1 LAST PATH I143
J 0
(-3050 2175);
DISPLAY 0.936170 (-3050 2175);
PAINT GREEN (-3050 2175);
DISPLAY INVISIBLE (-3050 2175);
FORCEADD TAP..6
(-3050 2125);
FORCEPROP 3 LASTPIN (-3000 2125) SIG_NAME M_F_ECC<0>
J 0
(-2990 2135);
DISPLAY 0.659574 (-2990 2135);
PAINT MONO (-2990 2135);
DISPLAY INVISIBLE (-2990 2135);
FORCEPROP 1 LASTPIN (-3000 2125) BN 0
J 0
(-3050 2135);
DISPLAY 0.617021 (-3050 2135);
PAINT PINK (-3050 2135);
FORCEPROP 2 LAST CDS_LIB mstr_standard
J 0
(-3050 2125);
DISPLAY 0.787234 (-3050 2125);
PAINT MONO (-3050 2125);
DISPLAY INVISIBLE (-3050 2125);
FORCEPROP 1 LAST BODY_TYPE PLUMBING
J 0
(-3050 2075);
DISPLAY 1.234043 (-3050 2075);
PAINT GREEN (-3050 2075);
DISPLAY INVISIBLE (-3050 2075);
FORCEPROP 1 LAST HDL_TAP TRUE
J 0
(-2725 2000);
DISPLAY 1.234043 (-2725 2000);
PAINT GREEN (-2725 2000);
DISPLAY INVISIBLE (-2725 2000);
FORCEPROP 1 LAST PATH I144
J 0
(-3050 2125);
DISPLAY 0.936170 (-3050 2125);
PAINT GREEN (-3050 2125);
DISPLAY INVISIBLE (-3050 2125);
FORCEADD TAP..6
(-3050 2075);
FORCEPROP 3 LASTPIN (-3000 2075) SIG_NAME M_F_ECC<1>
J 0
(-2990 2085);
DISPLAY 0.659574 (-2990 2085);
PAINT MONO (-2990 2085);
DISPLAY INVISIBLE (-2990 2085);
FORCEPROP 1 LASTPIN (-3000 2075) BN 1
J 0
(-3050 2085);
DISPLAY 0.617021 (-3050 2085);
PAINT PINK (-3050 2085);
FORCEPROP 2 LAST CDS_LIB mstr_standard
J 0
(-3050 2075);
DISPLAY 0.787234 (-3050 2075);
PAINT MONO (-3050 2075);
DISPLAY INVISIBLE (-3050 2075);
FORCEPROP 1 LAST BODY_TYPE PLUMBING
J 0
(-3050 2025);
DISPLAY 1.234043 (-3050 2025);
PAINT GREEN (-3050 2025);
DISPLAY INVISIBLE (-3050 2025);
FORCEPROP 1 LAST HDL_TAP TRUE
J 0
(-2725 1950);
DISPLAY 1.234043 (-2725 1950);
PAINT GREEN (-2725 1950);
DISPLAY INVISIBLE (-2725 1950);
FORCEPROP 1 LAST PATH I145
J 0
(-3050 2075);
DISPLAY 0.936170 (-3050 2075);
PAINT GREEN (-3050 2075);
DISPLAY INVISIBLE (-3050 2075);
FORCEADD OFFPAGE..1
(-3900 1775);
FORCEPROP 2 LAST $XR1 54 
J 0
(-4271 1775);
DISPLAY 0.638298 (-4271 1775);
PAINT MONO (-4271 1775);
FORCEPROP 2 LAST $XR0 28 
J 0
(-4181 1775);
DISPLAY 0.638298 (-4181 1775);
PAINT MONO (-4181 1775);
FORCEPROP 2 LAST CDS_LIB mstr_standard
J 0
(-3900 1775);
DISPLAY 0.787234 (-3900 1775);
PAINT MONO (-3900 1775);
DISPLAY INVISIBLE (-3900 1775);
FORCEPROP 1 LAST OFFPAGE TRUE
J 0
(-3575 1650);
DISPLAY 0.936170 (-3575 1650);
PAINT GREEN (-3575 1650);
DISPLAY INVISIBLE (-3575 1650);
FORCEPROP 1 LAST COMMENT_BODY TRUE
J 0
(-3775 1675);
DISPLAY 0.936170 (-3775 1675);
PAINT GREEN (-3775 1675);
DISPLAY INVISIBLE (-3775 1675);
FORCEPROP 2 LAST PATH I146
J 0
(-3850 1850);
DISPLAY 0.787234 (-3850 1850);
PAINT MONO (-3850 1850);
DISPLAY INVISIBLE (-3850 1850);
FORCEADD OFFPAGE..1
(-3700 2425);
FORCEPROP 2 LAST $XR1 54 
J 0
(-4071 2425);
DISPLAY 0.638298 (-4071 2425);
PAINT MONO (-4071 2425);
FORCEPROP 2 LAST $XR0 28 
J 0
(-3981 2425);
DISPLAY 0.638298 (-3981 2425);
PAINT MONO (-3981 2425);
FORCEPROP 2 LAST CDS_LIB mstr_standard
J 0
(-3700 2425);
DISPLAY 0.787234 (-3700 2425);
PAINT MONO (-3700 2425);
DISPLAY INVISIBLE (-3700 2425);
FORCEPROP 1 LAST OFFPAGE TRUE
J 0
(-3375 2300);
DISPLAY 0.936170 (-3375 2300);
PAINT GREEN (-3375 2300);
DISPLAY INVISIBLE (-3375 2300);
FORCEPROP 1 LAST COMMENT_BODY TRUE
J 0
(-3575 2325);
DISPLAY 0.936170 (-3575 2325);
PAINT GREEN (-3575 2325);
DISPLAY INVISIBLE (-3575 2325);
FORCEPROP 2 LAST PATH I147
J 0
(-3650 2500);
DISPLAY 0.787234 (-3650 2500);
PAINT MONO (-3650 2500);
DISPLAY INVISIBLE (-3650 2500);
FORCEADD OFFPAGE..5
(-3925 1825);
FORCEPROP 2 LAST $XR1 28 
J 0
(-4269 1825);
DISPLAY 0.638298 (-4269 1825);
PAINT MONO (-4269 1825);
FORCEPROP 2 LAST $XR0 54 
J 0
(-4179 1825);
DISPLAY 0.638298 (-4179 1825);
PAINT MONO (-4179 1825);
FORCEPROP 2 LAST CDS_LIB mstr_standard
J 0
(-3925 1825);
DISPLAY 0.787234 (-3925 1825);
PAINT MONO (-3925 1825);
DISPLAY INVISIBLE (-3925 1825);
FORCEPROP 1 LAST OFFPAGE TRUE
J 0
(-3600 1700);
DISPLAY 1.404255 (-3600 1700);
PAINT GREEN (-3600 1700);
DISPLAY INVISIBLE (-3600 1700);
FORCEPROP 1 LAST COMMENT_BODY TRUE
J 0
(-3825 1750);
DISPLAY 1.404255 (-3825 1750);
PAINT GREEN (-3825 1750);
DISPLAY INVISIBLE (-3825 1750);
FORCEPROP 2 LAST PATH I148
J 0
(-3875 1900);
DISPLAY 0.787234 (-3875 1900);
PAINT MONO (-3875 1900);
DISPLAY INVISIBLE (-3875 1900);
FORCEADD OFFPAGE..1
(-3700 2375);
FORCEPROP 2 LAST $XR5 54 
J 0
(-4371 2375);
DISPLAY 0.638298 (-4371 2375);
PAINT MONO (-4371 2375);
FORCEPROP 2 LAST $XR4 52 
J 0
(-4281 2375);
DISPLAY 0.638298 (-4281 2375);
PAINT MONO (-4281 2375);
FORCEPROP 2 LAST $XR3 51 
J 0
(-4191 2375);
DISPLAY 0.638298 (-4191 2375);
PAINT MONO (-4191 2375);
FORCEPROP 2 LAST $XR2 50 
J 0
(-4101 2375);
DISPLAY 0.638298 (-4101 2375);
PAINT MONO (-4101 2375);
FORCEPROP 2 LAST $XR1 49 
J 0
(-4011 2375);
DISPLAY 0.638298 (-4011 2375);
PAINT MONO (-4011 2375);
FORCEPROP 2 LAST $XR0 21 
J 0
(-3921 2375);
DISPLAY 0.638298 (-3921 2375);
PAINT MONO (-3921 2375);
FORCEPROP 2 LAST CDS_LIB mstr_standard
J 0
(-3700 2375);
DISPLAY 0.787234 (-3700 2375);
PAINT MONO (-3700 2375);
DISPLAY INVISIBLE (-3700 2375);
FORCEPROP 1 LAST OFFPAGE TRUE
J 0
(-3375 2250);
DISPLAY 0.936170 (-3375 2250);
PAINT GREEN (-3375 2250);
DISPLAY INVISIBLE (-3375 2250);
FORCEPROP 1 LAST COMMENT_BODY TRUE
J 0
(-3575 2275);
DISPLAY 0.936170 (-3575 2275);
PAINT GREEN (-3575 2275);
DISPLAY INVISIBLE (-3575 2275);
FORCEPROP 2 LAST PATH I149
J 0
(-3650 2450);
DISPLAY 0.787234 (-3650 2450);
PAINT MONO (-3650 2450);
DISPLAY INVISIBLE (-3650 2450);
FORCEADD TAP..6
R 2
(650 4700);
FORCEPROP 3 LASTPIN (600 4700) SIG_NAME M_F_DQS_DP<12>
J 0
(610 4710);
DISPLAY 0.659574 (610 4710);
PAINT MONO (610 4710);
DISPLAY INVISIBLE (610 4710);
FORCEPROP 1 LASTPIN (600 4700) BN 12
J 2
(650 4710);
DISPLAY 0.617021 (650 4710);
PAINT PINK (650 4710);
FORCEPROP 2 LAST CDS_LIB mstr_standard
J 0
(650 4700);
DISPLAY 0.787234 (650 4700);
PAINT MONO (650 4700);
DISPLAY INVISIBLE (650 4700);
FORCEPROP 1 LAST BODY_TYPE PLUMBING
J 2
(650 4650);
DISPLAY 1.234043 (650 4650);
PAINT GREEN (650 4650);
DISPLAY INVISIBLE (650 4650);
FORCEPROP 1 LAST HDL_TAP TRUE
J 2
(325 4575);
DISPLAY 1.234043 (325 4575);
PAINT GREEN (325 4575);
DISPLAY INVISIBLE (325 4575);
FORCEPROP 1 LAST PATH I15
J 2
(650 4700);
DISPLAY 0.936170 (650 4700);
PAINT GREEN (650 4700);
DISPLAY INVISIBLE (650 4700);
FORCEADD OFFPAGE..6
(-3700 2475);
FORCEPROP 2 LAST $XR1 54 
J 0
(-4069 2475);
DISPLAY 0.638298 (-4069 2475);
PAINT MONO (-4069 2475);
FORCEPROP 2 LAST $XR0 28 
J 0
(-3979 2475);
DISPLAY 0.638298 (-3979 2475);
PAINT MONO (-3979 2475);
FORCEPROP 2 LAST CDS_LIB mstr_standard
J 0
(-3700 2475);
DISPLAY 0.787234 (-3700 2475);
PAINT MONO (-3700 2475);
DISPLAY INVISIBLE (-3700 2475);
FORCEPROP 1 LAST OFFPAGE TRUE
J 0
(-3375 2350);
DISPLAY 0.936170 (-3375 2350);
PAINT GREEN (-3375 2350);
DISPLAY INVISIBLE (-3375 2350);
FORCEPROP 1 LAST COMMENT_BODY TRUE
J 0
(-3600 2400);
DISPLAY 0.936170 (-3600 2400);
PAINT GREEN (-3600 2400);
DISPLAY INVISIBLE (-3600 2400);
FORCEPROP 2 LAST PATH I150
J 0
(-3650 2550);
DISPLAY 0.787234 (-3650 2550);
PAINT MONO (-3650 2550);
DISPLAY INVISIBLE (-3650 2550);
FORCEADD TAP..6
(-3050 3275);
FORCEPROP 3 LASTPIN (-3000 3275) SIG_NAME M_F_CLK_DP<1>
J 0
(-2990 3285);
DISPLAY 0.659574 (-2990 3285);
PAINT MONO (-2990 3285);
DISPLAY INVISIBLE (-2990 3285);
FORCEPROP 1 LASTPIN (-3000 3275) BN 1
J 0
(-3050 3285);
DISPLAY 0.617021 (-3050 3285);
PAINT PINK (-3050 3285);
FORCEPROP 2 LAST CDS_LIB mstr_standard
J 0
(-3050 3275);
DISPLAY 0.787234 (-3050 3275);
PAINT MONO (-3050 3275);
DISPLAY INVISIBLE (-3050 3275);
FORCEPROP 1 LAST BODY_TYPE PLUMBING
J 0
(-3050 3225);
DISPLAY 1.234043 (-3050 3225);
PAINT GREEN (-3050 3225);
DISPLAY INVISIBLE (-3050 3225);
FORCEPROP 1 LAST HDL_TAP TRUE
J 0
(-2725 3150);
DISPLAY 1.234043 (-2725 3150);
PAINT GREEN (-2725 3150);
DISPLAY INVISIBLE (-2725 3150);
FORCEPROP 1 LAST PATH I152
J 0
(-3050 3275);
DISPLAY 0.936170 (-3050 3275);
PAINT GREEN (-3050 3275);
DISPLAY INVISIBLE (-3050 3275);
FORCEADD TAP..6
(-3050 3175);
FORCEPROP 3 LASTPIN (-3000 3175) SIG_NAME M_F_CLK_DP<0>
J 0
(-2990 3185);
DISPLAY 0.659574 (-2990 3185);
PAINT MONO (-2990 3185);
DISPLAY INVISIBLE (-2990 3185);
FORCEPROP 1 LASTPIN (-3000 3175) BN 0
J 0
(-3050 3185);
DISPLAY 0.617021 (-3050 3185);
PAINT PINK (-3050 3185);
FORCEPROP 2 LAST CDS_LIB mstr_standard
J 0
(-3050 3175);
DISPLAY 0.787234 (-3050 3175);
PAINT MONO (-3050 3175);
DISPLAY INVISIBLE (-3050 3175);
FORCEPROP 1 LAST BODY_TYPE PLUMBING
J 0
(-3050 3125);
DISPLAY 1.234043 (-3050 3125);
PAINT GREEN (-3050 3125);
DISPLAY INVISIBLE (-3050 3125);
FORCEPROP 1 LAST HDL_TAP TRUE
J 0
(-2725 3050);
DISPLAY 1.234043 (-2725 3050);
PAINT GREEN (-2725 3050);
DISPLAY INVISIBLE (-2725 3050);
FORCEPROP 1 LAST PATH I153
J 0
(-3050 3175);
DISPLAY 0.936170 (-3050 3175);
PAINT GREEN (-3050 3175);
DISPLAY INVISIBLE (-3050 3175);
FORCEADD TAP..6
(-3250 3225);
FORCEPROP 3 LASTPIN (-3200 3225) SIG_NAME M_F_CLK_DN<1>
J 0
(-3190 3235);
DISPLAY 0.659574 (-3190 3235);
PAINT MONO (-3190 3235);
DISPLAY INVISIBLE (-3190 3235);
FORCEPROP 1 LASTPIN (-3200 3225) BN 1
J 0
(-3250 3235);
DISPLAY 0.617021 (-3250 3235);
PAINT PINK (-3250 3235);
FORCEPROP 2 LAST CDS_LIB mstr_standard
J 0
(-3250 3225);
DISPLAY 0.787234 (-3250 3225);
PAINT MONO (-3250 3225);
DISPLAY INVISIBLE (-3250 3225);
FORCEPROP 1 LAST BODY_TYPE PLUMBING
J 0
(-3250 3175);
DISPLAY 1.234043 (-3250 3175);
PAINT GREEN (-3250 3175);
DISPLAY INVISIBLE (-3250 3175);
FORCEPROP 1 LAST HDL_TAP TRUE
J 0
(-2925 3100);
DISPLAY 1.234043 (-2925 3100);
PAINT GREEN (-2925 3100);
DISPLAY INVISIBLE (-2925 3100);
FORCEPROP 1 LAST PATH I154
J 0
(-3250 3225);
DISPLAY 0.936170 (-3250 3225);
PAINT GREEN (-3250 3225);
DISPLAY INVISIBLE (-3250 3225);
FORCEADD TAP..6
(-3250 3125);
FORCEPROP 3 LASTPIN (-3200 3125) SIG_NAME M_F_CLK_DN<0>
J 0
(-3190 3135);
DISPLAY 0.659574 (-3190 3135);
PAINT MONO (-3190 3135);
DISPLAY INVISIBLE (-3190 3135);
FORCEPROP 1 LASTPIN (-3200 3125) BN 0
J 0
(-3250 3135);
DISPLAY 0.617021 (-3250 3135);
PAINT PINK (-3250 3135);
FORCEPROP 2 LAST CDS_LIB mstr_standard
J 0
(-3250 3125);
DISPLAY 0.787234 (-3250 3125);
PAINT MONO (-3250 3125);
DISPLAY INVISIBLE (-3250 3125);
FORCEPROP 1 LAST BODY_TYPE PLUMBING
J 0
(-3250 3075);
DISPLAY 1.234043 (-3250 3075);
PAINT GREEN (-3250 3075);
DISPLAY INVISIBLE (-3250 3075);
FORCEPROP 1 LAST HDL_TAP TRUE
J 0
(-2925 3000);
DISPLAY 1.234043 (-2925 3000);
PAINT GREEN (-2925 3000);
DISPLAY INVISIBLE (-2925 3000);
FORCEPROP 1 LAST PATH I155
J 0
(-3250 3125);
DISPLAY 0.936170 (-3250 3125);
PAINT GREEN (-3250 3125);
DISPLAY INVISIBLE (-3250 3125);
FORCEADD OFFPAGE..1
(-3700 3325);
FORCEPROP 2 LAST $XR1 54 
J 0
(-4011 3325);
DISPLAY 0.638298 (-4011 3325);
PAINT MONO (-4011 3325);
FORCEPROP 2 LAST $XR0 28 
J 0
(-3921 3325);
DISPLAY 0.638298 (-3921 3325);
PAINT MONO (-3921 3325);
FORCEPROP 2 LAST CDS_LIB mstr_standard
J 0
(-3700 3325);
DISPLAY 0.787234 (-3700 3325);
PAINT MONO (-3700 3325);
DISPLAY INVISIBLE (-3700 3325);
FORCEPROP 1 LAST OFFPAGE TRUE
J 0
(-3375 3200);
DISPLAY 0.936170 (-3375 3200);
PAINT GREEN (-3375 3200);
DISPLAY INVISIBLE (-3375 3200);
FORCEPROP 1 LAST COMMENT_BODY TRUE
J 0
(-3575 3225);
DISPLAY 0.936170 (-3575 3225);
PAINT GREEN (-3575 3225);
DISPLAY INVISIBLE (-3575 3225);
FORCEPROP 2 LAST PATH I156
J 0
(-3650 3400);
DISPLAY 0.787234 (-3650 3400);
PAINT MONO (-3650 3400);
DISPLAY INVISIBLE (-3650 3400);
FORCEADD OFFPAGE..1
(-3700 3275);
FORCEPROP 2 LAST $XR1 54 
J 0
(-4011 3275);
DISPLAY 0.638298 (-4011 3275);
PAINT MONO (-4011 3275);
FORCEPROP 2 LAST $XR0 28 
J 0
(-3921 3275);
DISPLAY 0.638298 (-3921 3275);
PAINT MONO (-3921 3275);
FORCEPROP 2 LAST CDS_LIB mstr_standard
J 0
(-3700 3275);
DISPLAY 0.787234 (-3700 3275);
PAINT MONO (-3700 3275);
DISPLAY INVISIBLE (-3700 3275);
FORCEPROP 1 LAST OFFPAGE TRUE
J 0
(-3375 3150);
DISPLAY 0.936170 (-3375 3150);
PAINT GREEN (-3375 3150);
DISPLAY INVISIBLE (-3375 3150);
FORCEPROP 1 LAST COMMENT_BODY TRUE
J 0
(-3575 3175);
DISPLAY 0.936170 (-3575 3175);
PAINT GREEN (-3575 3175);
DISPLAY INVISIBLE (-3575 3175);
FORCEPROP 2 LAST PATH I157
J 0
(-3650 3350);
DISPLAY 0.787234 (-3650 3350);
PAINT MONO (-3650 3350);
DISPLAY INVISIBLE (-3650 3350);
FORCEADD TAP..6
(-3050 2975);
FORCEPROP 3 LASTPIN (-3000 2975) SIG_NAME M_F_CS_N<3>
J 0
(-2990 2985);
DISPLAY 0.659574 (-2990 2985);
PAINT MONO (-2990 2985);
DISPLAY INVISIBLE (-2990 2985);
FORCEPROP 1 LASTPIN (-3000 2975) BN 3
J 0
(-3050 2985);
DISPLAY 0.617021 (-3050 2985);
PAINT PINK (-3050 2985);
FORCEPROP 2 LAST CDS_LIB mstr_standard
J 0
(-3050 2975);
DISPLAY 0.787234 (-3050 2975);
PAINT MONO (-3050 2975);
DISPLAY INVISIBLE (-3050 2975);
FORCEPROP 1 LAST BODY_TYPE PLUMBING
J 0
(-3050 2925);
DISPLAY 1.234043 (-3050 2925);
PAINT GREEN (-3050 2925);
DISPLAY INVISIBLE (-3050 2925);
FORCEPROP 1 LAST HDL_TAP TRUE
J 0
(-2725 2850);
DISPLAY 1.234043 (-2725 2850);
PAINT GREEN (-2725 2850);
DISPLAY INVISIBLE (-2725 2850);
FORCEPROP 1 LAST PATH I158
J 0
(-3050 2975);
DISPLAY 0.936170 (-3050 2975);
PAINT GREEN (-3050 2975);
DISPLAY INVISIBLE (-3050 2975);
FORCEADD TAP..6
(-3050 2925);
FORCEPROP 3 LASTPIN (-3000 2925) SIG_NAME M_F_CS_N<2>
J 0
(-2990 2935);
DISPLAY 0.659574 (-2990 2935);
PAINT MONO (-2990 2935);
DISPLAY INVISIBLE (-2990 2935);
FORCEPROP 1 LASTPIN (-3000 2925) BN 2
J 0
(-3050 2935);
DISPLAY 0.617021 (-3050 2935);
PAINT PINK (-3050 2935);
FORCEPROP 2 LAST CDS_LIB mstr_standard
J 0
(-3050 2925);
DISPLAY 0.787234 (-3050 2925);
PAINT MONO (-3050 2925);
DISPLAY INVISIBLE (-3050 2925);
FORCEPROP 1 LAST BODY_TYPE PLUMBING
J 0
(-3050 2875);
DISPLAY 1.234043 (-3050 2875);
PAINT GREEN (-3050 2875);
DISPLAY INVISIBLE (-3050 2875);
FORCEPROP 1 LAST HDL_TAP TRUE
J 0
(-2725 2800);
DISPLAY 1.234043 (-2725 2800);
PAINT GREEN (-2725 2800);
DISPLAY INVISIBLE (-2725 2800);
FORCEPROP 1 LAST PATH I159
J 0
(-3050 2925);
DISPLAY 0.936170 (-3050 2925);
PAINT GREEN (-3050 2925);
DISPLAY INVISIBLE (-3050 2925);
FORCEADD TAP..6
(-3050 2875);
FORCEPROP 3 LASTPIN (-3000 2875) SIG_NAME M_F_CS_N<1>
J 0
(-2990 2885);
DISPLAY 0.659574 (-2990 2885);
PAINT MONO (-2990 2885);
DISPLAY INVISIBLE (-2990 2885);
FORCEPROP 1 LASTPIN (-3000 2875) BN 1
J 0
(-3050 2885);
DISPLAY 0.617021 (-3050 2885);
PAINT PINK (-3050 2885);
FORCEPROP 2 LAST CDS_LIB mstr_standard
J 0
(-3050 2875);
DISPLAY 0.787234 (-3050 2875);
PAINT MONO (-3050 2875);
DISPLAY INVISIBLE (-3050 2875);
FORCEPROP 1 LAST BODY_TYPE PLUMBING
J 0
(-3050 2825);
DISPLAY 1.234043 (-3050 2825);
PAINT GREEN (-3050 2825);
DISPLAY INVISIBLE (-3050 2825);
FORCEPROP 1 LAST HDL_TAP TRUE
J 0
(-2725 2750);
DISPLAY 1.234043 (-2725 2750);
PAINT GREEN (-2725 2750);
DISPLAY INVISIBLE (-2725 2750);
FORCEPROP 1 LAST PATH I160
J 0
(-3050 2875);
DISPLAY 0.936170 (-3050 2875);
PAINT GREEN (-3050 2875);
DISPLAY INVISIBLE (-3050 2875);
FORCEADD TAP..6
(-3050 2825);
FORCEPROP 3 LASTPIN (-3000 2825) SIG_NAME M_F_CS_N<0>
J 0
(-2990 2835);
DISPLAY 0.659574 (-2990 2835);
PAINT MONO (-2990 2835);
DISPLAY INVISIBLE (-2990 2835);
FORCEPROP 1 LASTPIN (-3000 2825) BN 0
J 0
(-3050 2835);
DISPLAY 0.617021 (-3050 2835);
PAINT PINK (-3050 2835);
FORCEPROP 2 LAST CDS_LIB mstr_standard
J 0
(-3050 2825);
DISPLAY 0.787234 (-3050 2825);
PAINT MONO (-3050 2825);
DISPLAY INVISIBLE (-3050 2825);
FORCEPROP 1 LAST BODY_TYPE PLUMBING
J 0
(-3050 2775);
DISPLAY 1.234043 (-3050 2775);
PAINT GREEN (-3050 2775);
DISPLAY INVISIBLE (-3050 2775);
FORCEPROP 1 LAST HDL_TAP TRUE
J 0
(-2725 2700);
DISPLAY 1.234043 (-2725 2700);
PAINT GREEN (-2725 2700);
DISPLAY INVISIBLE (-2725 2700);
FORCEPROP 1 LAST PATH I161
J 0
(-3050 2825);
DISPLAY 0.936170 (-3050 2825);
PAINT GREEN (-3050 2825);
DISPLAY INVISIBLE (-3050 2825);
FORCEADD TAP..6
(-3050 2725);
FORCEPROP 3 LASTPIN (-3000 2725) SIG_NAME M_F_CKE<1>
J 0
(-2990 2735);
DISPLAY 0.659574 (-2990 2735);
PAINT MONO (-2990 2735);
DISPLAY INVISIBLE (-2990 2735);
FORCEPROP 1 LASTPIN (-3000 2725) BN 1
J 0
(-3050 2735);
DISPLAY 0.617021 (-3050 2735);
PAINT PINK (-3050 2735);
FORCEPROP 2 LAST CDS_LIB mstr_standard
J 0
(-3050 2725);
DISPLAY 0.787234 (-3050 2725);
PAINT MONO (-3050 2725);
DISPLAY INVISIBLE (-3050 2725);
FORCEPROP 1 LAST BODY_TYPE PLUMBING
J 0
(-3050 2675);
DISPLAY 1.234043 (-3050 2675);
PAINT GREEN (-3050 2675);
DISPLAY INVISIBLE (-3050 2675);
FORCEPROP 1 LAST HDL_TAP TRUE
J 0
(-2725 2600);
DISPLAY 1.234043 (-2725 2600);
PAINT GREEN (-2725 2600);
DISPLAY INVISIBLE (-2725 2600);
FORCEPROP 1 LAST PATH I162
J 0
(-3050 2725);
DISPLAY 0.936170 (-3050 2725);
PAINT GREEN (-3050 2725);
DISPLAY INVISIBLE (-3050 2725);
FORCEADD TAP..6
(-3050 2675);
FORCEPROP 3 LASTPIN (-3000 2675) SIG_NAME M_F_CKE<0>
J 0
(-2990 2685);
DISPLAY 0.659574 (-2990 2685);
PAINT MONO (-2990 2685);
DISPLAY INVISIBLE (-2990 2685);
FORCEPROP 1 LASTPIN (-3000 2675) BN 0
J 0
(-3050 2685);
DISPLAY 0.617021 (-3050 2685);
PAINT PINK (-3050 2685);
FORCEPROP 2 LAST CDS_LIB mstr_standard
J 0
(-3050 2675);
DISPLAY 0.787234 (-3050 2675);
PAINT MONO (-3050 2675);
DISPLAY INVISIBLE (-3050 2675);
FORCEPROP 1 LAST BODY_TYPE PLUMBING
J 0
(-3050 2625);
DISPLAY 1.234043 (-3050 2625);
PAINT GREEN (-3050 2625);
DISPLAY INVISIBLE (-3050 2625);
FORCEPROP 1 LAST HDL_TAP TRUE
J 0
(-2725 2550);
DISPLAY 1.234043 (-2725 2550);
PAINT GREEN (-2725 2550);
DISPLAY INVISIBLE (-2725 2550);
FORCEPROP 1 LAST PATH I163
J 0
(-3050 2675);
DISPLAY 0.936170 (-3050 2675);
PAINT GREEN (-3050 2675);
DISPLAY INVISIBLE (-3050 2675);
FORCEADD TAP..6
(-3050 2575);
FORCEPROP 3 LASTPIN (-3000 2575) SIG_NAME M_F_ODT<1>
J 0
(-2990 2585);
DISPLAY 0.659574 (-2990 2585);
PAINT MONO (-2990 2585);
DISPLAY INVISIBLE (-2990 2585);
FORCEPROP 1 LASTPIN (-3000 2575) BN 1
J 0
(-3050 2585);
DISPLAY 0.617021 (-3050 2585);
PAINT PINK (-3050 2585);
FORCEPROP 2 LAST CDS_LIB mstr_standard
J 0
(-3050 2575);
DISPLAY 0.787234 (-3050 2575);
PAINT MONO (-3050 2575);
DISPLAY INVISIBLE (-3050 2575);
FORCEPROP 1 LAST BODY_TYPE PLUMBING
J 0
(-3050 2525);
DISPLAY 1.234043 (-3050 2525);
PAINT GREEN (-3050 2525);
DISPLAY INVISIBLE (-3050 2525);
FORCEPROP 1 LAST HDL_TAP TRUE
J 0
(-2725 2450);
DISPLAY 1.234043 (-2725 2450);
PAINT GREEN (-2725 2450);
DISPLAY INVISIBLE (-2725 2450);
FORCEPROP 1 LAST PATH I164
J 0
(-3050 2575);
DISPLAY 0.936170 (-3050 2575);
PAINT GREEN (-3050 2575);
DISPLAY INVISIBLE (-3050 2575);
FORCEADD TAP..6
(-3050 2525);
FORCEPROP 3 LASTPIN (-3000 2525) SIG_NAME M_F_ODT<0>
J 0
(-2990 2535);
DISPLAY 0.659574 (-2990 2535);
PAINT MONO (-2990 2535);
DISPLAY INVISIBLE (-2990 2535);
FORCEPROP 1 LASTPIN (-3000 2525) BN 0
J 0
(-3050 2535);
DISPLAY 0.617021 (-3050 2535);
PAINT PINK (-3050 2535);
FORCEPROP 2 LAST CDS_LIB mstr_standard
J 0
(-3050 2525);
DISPLAY 0.787234 (-3050 2525);
PAINT MONO (-3050 2525);
DISPLAY INVISIBLE (-3050 2525);
FORCEPROP 1 LAST BODY_TYPE PLUMBING
J 0
(-3050 2475);
DISPLAY 1.234043 (-3050 2475);
PAINT GREEN (-3050 2475);
DISPLAY INVISIBLE (-3050 2475);
FORCEPROP 1 LAST HDL_TAP TRUE
J 0
(-2725 2400);
DISPLAY 1.234043 (-2725 2400);
PAINT GREEN (-2725 2400);
DISPLAY INVISIBLE (-2725 2400);
FORCEPROP 1 LAST PATH I165
J 0
(-3050 2525);
DISPLAY 0.936170 (-3050 2525);
PAINT GREEN (-3050 2525);
DISPLAY INVISIBLE (-3050 2525);
FORCEADD OFFPAGE..1
(-3700 3025);
FORCEPROP 2 LAST $XR1 54 
J 0
(-4011 3025);
DISPLAY 0.638298 (-4011 3025);
PAINT MONO (-4011 3025);
FORCEPROP 2 LAST $XR0 28 
J 0
(-3921 3025);
DISPLAY 0.638298 (-3921 3025);
PAINT MONO (-3921 3025);
FORCEPROP 2 LAST CDS_LIB mstr_standard
J 0
(-3700 3025);
DISPLAY 0.787234 (-3700 3025);
PAINT MONO (-3700 3025);
DISPLAY INVISIBLE (-3700 3025);
FORCEPROP 1 LAST OFFPAGE TRUE
J 0
(-3375 2900);
DISPLAY 0.936170 (-3375 2900);
PAINT GREEN (-3375 2900);
DISPLAY INVISIBLE (-3375 2900);
FORCEPROP 1 LAST COMMENT_BODY TRUE
J 0
(-3575 2925);
DISPLAY 0.936170 (-3575 2925);
PAINT GREEN (-3575 2925);
DISPLAY INVISIBLE (-3575 2925);
FORCEPROP 2 LAST PATH I166
J 0
(-3650 3100);
DISPLAY 0.787234 (-3650 3100);
PAINT MONO (-3650 3100);
DISPLAY INVISIBLE (-3650 3100);
FORCEADD OFFPAGE..1
(-3700 2775);
FORCEPROP 2 LAST $XR1 54 
J 0
(-4011 2775);
DISPLAY 0.638298 (-4011 2775);
PAINT MONO (-4011 2775);
FORCEPROP 2 LAST $XR0 28 
J 0
(-3921 2775);
DISPLAY 0.638298 (-3921 2775);
PAINT MONO (-3921 2775);
FORCEPROP 2 LAST CDS_LIB mstr_standard
J 0
(-3700 2775);
DISPLAY 0.787234 (-3700 2775);
PAINT MONO (-3700 2775);
DISPLAY INVISIBLE (-3700 2775);
FORCEPROP 1 LAST OFFPAGE TRUE
J 0
(-3375 2650);
DISPLAY 0.936170 (-3375 2650);
PAINT GREEN (-3375 2650);
DISPLAY INVISIBLE (-3375 2650);
FORCEPROP 1 LAST COMMENT_BODY TRUE
J 0
(-3575 2675);
DISPLAY 0.936170 (-3575 2675);
PAINT GREEN (-3575 2675);
DISPLAY INVISIBLE (-3575 2675);
FORCEPROP 2 LAST PATH I167
J 0
(-3650 2850);
DISPLAY 0.787234 (-3650 2850);
PAINT MONO (-3650 2850);
DISPLAY INVISIBLE (-3650 2850);
FORCEADD OFFPAGE..1
(-3700 2625);
FORCEPROP 2 LAST $XR1 54 
J 0
(-4011 2625);
DISPLAY 0.638298 (-4011 2625);
PAINT MONO (-4011 2625);
FORCEPROP 2 LAST $XR0 28 
J 0
(-3921 2625);
DISPLAY 0.638298 (-3921 2625);
PAINT MONO (-3921 2625);
FORCEPROP 2 LAST CDS_LIB mstr_standard
J 0
(-3700 2625);
DISPLAY 0.787234 (-3700 2625);
PAINT MONO (-3700 2625);
DISPLAY INVISIBLE (-3700 2625);
FORCEPROP 1 LAST OFFPAGE TRUE
J 0
(-3375 2500);
DISPLAY 0.936170 (-3375 2500);
PAINT GREEN (-3375 2500);
DISPLAY INVISIBLE (-3375 2500);
FORCEPROP 1 LAST COMMENT_BODY TRUE
J 0
(-3575 2525);
DISPLAY 0.936170 (-3575 2525);
PAINT GREEN (-3575 2525);
DISPLAY INVISIBLE (-3575 2525);
FORCEPROP 2 LAST PATH I168
J 0
(-3650 2700);
DISPLAY 0.787234 (-3650 2700);
PAINT MONO (-3650 2700);
DISPLAY INVISIBLE (-3650 2700);
FORCEADD OFFPAGE..1
(-3700 1425);
FORCEPROP 2 LAST $XR5 54 
J 0
(-4431 1425);
DISPLAY 0.638298 (-4431 1425);
PAINT MONO (-4431 1425);
FORCEPROP 2 LAST $XR4 52 
J 0
(-4341 1425);
DISPLAY 0.638298 (-4341 1425);
PAINT MONO (-4341 1425);
FORCEPROP 2 LAST $XR3 51 
J 0
(-4251 1425);
DISPLAY 0.638298 (-4251 1425);
PAINT MONO (-4251 1425);
FORCEPROP 2 LAST $XR2 50 
J 0
(-4161 1425);
DISPLAY 0.638298 (-4161 1425);
PAINT MONO (-4161 1425);
FORCEPROP 2 LAST $XR1 49 
J 0
(-4071 1425);
DISPLAY 0.638298 (-4071 1425);
PAINT MONO (-4071 1425);
FORCEPROP 2 LAST $XR0 99 
J 0
(-3981 1425);
DISPLAY 0.638298 (-3981 1425);
PAINT MONO (-3981 1425);
FORCEPROP 2 LAST CDS_LIB mstr_standard
J 0
(-3700 1425);
DISPLAY 0.787234 (-3700 1425);
PAINT MONO (-3700 1425);
DISPLAY INVISIBLE (-3700 1425);
FORCEPROP 1 LAST OFFPAGE TRUE
J 0
(-3375 1300);
DISPLAY 0.936170 (-3375 1300);
PAINT GREEN (-3375 1300);
DISPLAY INVISIBLE (-3375 1300);
FORCEPROP 1 LAST COMMENT_BODY TRUE
J 0
(-3575 1325);
DISPLAY 0.936170 (-3575 1325);
PAINT GREEN (-3575 1325);
DISPLAY INVISIBLE (-3575 1325);
FORCEPROP 2 LAST PATH I169
J 0
(-3650 1500);
DISPLAY 0.787234 (-3650 1500);
PAINT MONO (-3650 1500);
DISPLAY INVISIBLE (-3650 1500);
FORCEADD PVTT_DEF..1
(-1100 2750);
FORCEPROP 3 LASTPIN (-1100 2700) SIG_NAME PVTT_DEF\g
J 0
(-1090 2710);
DISPLAY 0.659574 (-1090 2710);
PAINT MONO (-1090 2710);
DISPLAY INVISIBLE (-1090 2710);
FORCEPROP 1 LAST VOLTAGE 0.6V
J 0
(-1145 2707);
DISPLAY 0.340426 (-1145 2707);
PAINT SKYBLUE (-1145 2707);
DISPLAY INVISIBLE (-1145 2707);
FORCEPROP 2 LAST BOM_COST MEM
J 0
(-1100 2755);
PAINT ORANGE (-1100 2755);
DISPLAY INVISIBLE (-1100 2755);
FORCEPROP 2 LAST CDS_LIB mstr_symbols
J 0
(-1100 2750);
PAINT ORANGE (-1100 2750);
DISPLAY INVISIBLE (-1100 2750);
FORCEPROP 1 LAST BODY_TYPE PLUMBING
J 0
(-1145 2707);
DISPLAY 0.340426 (-1145 2707);
PAINT GREEN (-1145 2707);
DISPLAY INVISIBLE (-1145 2707);
FORCEPROP 1 LAST PATH I17
J 0
(-1050 2775);
DISPLAY 0.872340 (-1050 2775);
PAINT AQUA (-1050 2775);
DISPLAY INVISIBLE (-1050 2775);
FORCEPROP 2 LAST ROOM DDR4_CH_C
J 0
(-1100 2850);
DISPLAY 0.787234 (-1100 2850);
PAINT ORANGE (-1100 2850);
DISPLAY INVISIBLE (-1100 2850);
FORCEPROP 1 LAST HDL_POWER PVTT_DEF
J 1
(-1100 2800);
DISPLAY 0.872340 (-1100 2800);
PAINT GREEN (-1100 2800);
DISPLAY INVISIBLE (-1100 2800);
FORCEADD OFFPAGE..6
(-3700 1475);
FORCEPROP 2 LAST $XR5 99 
J 0
(-4429 1475);
DISPLAY 0.638298 (-4429 1475);
PAINT MONO (-4429 1475);
FORCEPROP 2 LAST $XR4 54 
J 0
(-4339 1475);
DISPLAY 0.638298 (-4339 1475);
PAINT MONO (-4339 1475);
FORCEPROP 2 LAST $XR3 52 
J 0
(-4249 1475);
DISPLAY 0.638298 (-4249 1475);
PAINT MONO (-4249 1475);
FORCEPROP 2 LAST $XR2 51 
J 0
(-4159 1475);
DISPLAY 0.638298 (-4159 1475);
PAINT MONO (-4159 1475);
FORCEPROP 2 LAST $XR1 50 
J 0
(-4069 1475);
DISPLAY 0.638298 (-4069 1475);
PAINT MONO (-4069 1475);
FORCEPROP 2 LAST $XR0 49 
J 0
(-3979 1475);
DISPLAY 0.638298 (-3979 1475);
PAINT MONO (-3979 1475);
FORCEPROP 2 LAST CDS_LIB mstr_standard
J 0
(-3700 1475);
DISPLAY 0.787234 (-3700 1475);
PAINT MONO (-3700 1475);
DISPLAY INVISIBLE (-3700 1475);
FORCEPROP 1 LAST OFFPAGE TRUE
J 0
(-3375 1350);
DISPLAY 0.936170 (-3375 1350);
PAINT GREEN (-3375 1350);
DISPLAY INVISIBLE (-3375 1350);
FORCEPROP 1 LAST COMMENT_BODY TRUE
J 0
(-3600 1400);
DISPLAY 0.936170 (-3600 1400);
PAINT GREEN (-3600 1400);
DISPLAY INVISIBLE (-3600 1400);
FORCEPROP 2 LAST PATH I170
J 0
(-3650 1550);
DISPLAY 0.787234 (-3650 1550);
PAINT MONO (-3650 1550);
DISPLAY INVISIBLE (-3650 1550);
FORCEADD SCONN288_H44441004..4
(-250 2050);
FORCEPROP 1 LAST LOCATION J4A1
J 0
(-700 3150);
DISPLAY 0.617021 (-700 3150);
PAINT AQUA (-700 3150);
FORCEPROP 1 LAST PART_NUMBER H44441-004
J 0
(-700 1000);
DISPLAY 0.617021 (-700 1000);
PAINT BLUE (-700 1000);
FORCEPROP 2 LASTPIN (-750 2600) $PN 77
J 2
(-760 2610);
DISPLAY 0.617021 (-760 2610);
PAINT ORANGE (-760 2610);
FORCEPROP 2 LASTPIN (-750 2550) $PN 221
J 2
(-760 2560);
DISPLAY 0.617021 (-760 2560);
PAINT ORANGE (-760 2560);
FORCEPROP 2 LASTPIN (-750 2900) $PN 142
J 2
(-760 2910);
DISPLAY 0.617021 (-760 2910);
PAINT ORANGE (-760 2910);
FORCEPROP 2 LASTPIN (-750 2850) $PN 143
J 2
(-760 2860);
DISPLAY 0.617021 (-760 2860);
PAINT ORANGE (-760 2860);
FORCEPROP 2 LASTPIN (-750 2800) $PN 288
J 2
(-760 2810);
DISPLAY 0.617021 (-760 2810);
PAINT ORANGE (-760 2810);
FORCEPROP 2 LASTPIN (-750 2750) $PN 286
J 2
(-760 2760);
DISPLAY 0.617021 (-760 2760);
PAINT ORANGE (-760 2760);
FORCEPROP 2 LASTPIN (-750 2700) $PN 287
J 2
(-760 2710);
DISPLAY 0.617021 (-760 2710);
PAINT ORANGE (-760 2710);
FORCEPROP 2 LASTPIN (-750 2450) $PN 59
J 2
(-760 2460);
DISPLAY 0.617021 (-760 2460);
PAINT ORANGE (-760 2460);
FORCEPROP 2 LASTPIN (-750 2400) $PN 61
J 2
(-760 2410);
DISPLAY 0.617021 (-760 2410);
PAINT ORANGE (-760 2410);
FORCEPROP 2 LASTPIN (-750 2350) $PN 64
J 2
(-760 2360);
DISPLAY 0.617021 (-760 2360);
PAINT ORANGE (-760 2360);
FORCEPROP 2 LASTPIN (-750 2300) $PN 67
J 2
(-760 2310);
DISPLAY 0.617021 (-760 2310);
PAINT ORANGE (-760 2310);
FORCEPROP 2 LASTPIN (-750 2250) $PN 70
J 2
(-760 2260);
DISPLAY 0.617021 (-760 2260);
PAINT ORANGE (-760 2260);
FORCEPROP 2 LASTPIN (-750 2200) $PN 73
J 2
(-760 2210);
DISPLAY 0.617021 (-760 2210);
PAINT ORANGE (-760 2210);
FORCEPROP 2 LASTPIN (-750 2150) $PN 76
J 2
(-760 2160);
DISPLAY 0.617021 (-760 2160);
PAINT ORANGE (-760 2160);
FORCEPROP 2 LASTPIN (-750 2100) $PN 80
J 2
(-760 2110);
DISPLAY 0.617021 (-760 2110);
PAINT ORANGE (-760 2110);
FORCEPROP 2 LASTPIN (-750 2050) $PN 83
J 2
(-760 2060);
DISPLAY 0.617021 (-760 2060);
PAINT ORANGE (-760 2060);
FORCEPROP 2 LASTPIN (-750 2000) $PN 85
J 2
(-760 2010);
DISPLAY 0.617021 (-760 2010);
PAINT ORANGE (-760 2010);
FORCEPROP 2 LASTPIN (-750 1950) $PN 88
J 2
(-760 1960);
DISPLAY 0.617021 (-760 1960);
PAINT ORANGE (-760 1960);
FORCEPROP 2 LASTPIN (-750 1900) $PN 90
J 2
(-760 1910);
DISPLAY 0.617021 (-760 1910);
PAINT ORANGE (-760 1910);
FORCEPROP 2 LASTPIN (-750 1850) $PN 92
J 2
(-760 1860);
DISPLAY 0.617021 (-760 1860);
PAINT ORANGE (-760 1860);
FORCEPROP 2 LASTPIN (-750 1800) $PN 204
J 2
(-760 1810);
DISPLAY 0.617021 (-760 1810);
PAINT ORANGE (-760 1810);
FORCEPROP 2 LASTPIN (-750 1750) $PN 206
J 2
(-760 1760);
DISPLAY 0.617021 (-760 1760);
PAINT ORANGE (-760 1760);
FORCEPROP 2 LASTPIN (-750 1700) $PN 209
J 2
(-760 1710);
DISPLAY 0.617021 (-760 1710);
PAINT ORANGE (-760 1710);
FORCEPROP 2 LASTPIN (-750 1650) $PN 212
J 2
(-760 1660);
DISPLAY 0.617021 (-760 1660);
PAINT ORANGE (-760 1660);
FORCEPROP 2 LASTPIN (-750 1600) $PN 215
J 2
(-760 1610);
DISPLAY 0.617021 (-760 1610);
PAINT ORANGE (-760 1610);
FORCEPROP 2 LASTPIN (-750 1550) $PN 217
J 2
(-760 1560);
DISPLAY 0.617021 (-760 1560);
PAINT ORANGE (-760 1560);
FORCEPROP 2 LASTPIN (-750 1500) $PN 220
J 2
(-760 1510);
DISPLAY 0.617021 (-760 1510);
PAINT ORANGE (-760 1510);
FORCEPROP 2 LASTPIN (-750 1450) $PN 223
J 2
(-760 1460);
DISPLAY 0.617021 (-760 1460);
PAINT ORANGE (-760 1460);
FORCEPROP 2 LASTPIN (-750 1400) $PN 226
J 2
(-760 1410);
DISPLAY 0.617021 (-760 1410);
PAINT ORANGE (-760 1410);
FORCEPROP 2 LASTPIN (-750 1350) $PN 229
J 2
(-760 1360);
DISPLAY 0.617021 (-760 1360);
PAINT ORANGE (-760 1360);
FORCEPROP 2 LASTPIN (-750 1300) $PN 231
J 2
(-760 1310);
DISPLAY 0.617021 (-760 1310);
PAINT ORANGE (-760 1310);
FORCEPROP 2 LASTPIN (-750 1250) $PN 233
J 2
(-760 1260);
DISPLAY 0.617021 (-760 1260);
PAINT ORANGE (-760 1260);
FORCEPROP 2 LASTPIN (-750 1200) $PN 236
J 2
(-760 1210);
DISPLAY 0.617021 (-760 1210);
PAINT ORANGE (-760 1210);
FORCEPROP 2 LASTPIN (250 2900) $PN 1
J 0
(260 2910);
DISPLAY 0.617021 (260 2910);
PAINT ORANGE (260 2910);
FORCEPROP 2 LASTPIN (250 2850) $PN 145
J 0
(260 2860);
DISPLAY 0.617021 (260 2860);
PAINT ORANGE (260 2860);
FORCEPROP 1 LAST MATERIAL SCONN
J 0
(-700 3100);
DISPLAY 0.617021 (-700 3100);
PAINT SKYBLUE (-700 3100);
FORCEPROP 1 LAST PACK_TYPE PIP
J 0
(-700 3200);
PAINT SKYBLUE (-700 3200);
DISPLAY INVISIBLE (-700 3200);
FORCEPROP 2 LAST BOM_COST MEM
J 0
(-250 2050);
PAINT ORANGE (-250 2050);
DISPLAY INVISIBLE (-250 2050);
FORCEPROP 2 LAST CDS_LIB mstr_sconn
J 0
(-250 2050);
PAINT ORANGE (-250 2050);
DISPLAY INVISIBLE (-250 2050);
FORCEPROP 2 LAST SEC_TYPE PIP
J 0
(-700 3200);
DISPLAY 1.021277 (-700 3200);
PAINT ORANGE (-700 3200);
DISPLAY INVISIBLE (-700 3200);
FORCEPROP 2 LAST SEC 4
J 0
(-700 3200);
DISPLAY 0.680851 (-700 3200);
PAINT MONO (-700 3200);
DISPLAY INVISIBLE (-700 3200);
FORCEPROP 2 LAST CDS_LOCATION J4A1
J 0
(-700 3150);
DISPLAY 0.617021 (-700 3150);
PAINT AQUA (-700 3150);
DISPLAY INVISIBLE (-700 3150);
FORCEPROP 1 LAST PATH I171
J 0
(-250 3100);
PAINT GREEN (-250 3100);
DISPLAY INVISIBLE (-250 3100);
FORCEPROP 2 LAST ROOM DDR4_CH_F
J 0
(-250 2050);
PAINT ORANGE (-250 2050);
DISPLAY INVISIBLE (-250 2050);
FORCEADD PVDDQ_DEF..1
(-1275 2600);
FORCEPROP 3 LASTPIN (-1275 2550) SIG_NAME PVDDQ_DEF\g
J 0
(-1265 2560);
DISPLAY 0.659574 (-1265 2560);
PAINT MONO (-1265 2560);
DISPLAY INVISIBLE (-1265 2560);
FORCEPROP 1 LAST VOLTAGE 1.2V
J 0
(-1320 2557);
DISPLAY 0.340426 (-1320 2557);
PAINT SKYBLUE (-1320 2557);
DISPLAY INVISIBLE (-1320 2557);
FORCEPROP 2 LAST BOM_COST MEM
J 0
(-1275 2605);
PAINT ORANGE (-1275 2605);
DISPLAY INVISIBLE (-1275 2605);
FORCEPROP 2 LAST CDS_LIB mstr_symbols
J 0
(-1275 2600);
PAINT ORANGE (-1275 2600);
DISPLAY INVISIBLE (-1275 2600);
FORCEPROP 1 LAST BODY_TYPE PLUMBING
J 0
(-1320 2557);
DISPLAY 0.340426 (-1320 2557);
PAINT GREEN (-1320 2557);
DISPLAY INVISIBLE (-1320 2557);
FORCEPROP 1 LAST PATH I172
J 0
(-1225 2625);
DISPLAY 0.872340 (-1225 2625);
PAINT AQUA (-1225 2625);
DISPLAY INVISIBLE (-1225 2625);
FORCEPROP 2 LAST ROOM DDR4_CH_C
J 0
(-1275 2700);
DISPLAY 0.787234 (-1275 2700);
PAINT ORANGE (-1275 2700);
DISPLAY INVISIBLE (-1275 2700);
FORCEPROP 1 LAST HDL_POWER PVDDQ_DEF
J 1
(-1275 2650);
DISPLAY 0.872340 (-1275 2650);
PAINT GREEN (-1275 2650);
DISPLAY INVISIBLE (-1275 2650);
FORCEADD GND..1
R 2
(2450 1100);
FORCEPROP 3 LASTPIN (2450 1150) SIG_NAME GND\g
J 0
(2460 1160);
DISPLAY 0.659574 (2460 1160);
PAINT MONO (2460 1160);
DISPLAY INVISIBLE (2460 1160);
FORCEPROP 1 LAST VOLTAGE 0
J 0
(2450 1100);
PAINT SKYBLUE (2450 1100);
DISPLAY INVISIBLE (2450 1100);
FORCEPROP 2 LAST BOM_COST MEM
J 0
(2450 1105);
PAINT ORANGE (2450 1105);
DISPLAY INVISIBLE (2450 1105);
FORCEPROP 1 LAST SIZE 1B
J 2
(2375 1050);
DISPLAY 1.170213 (2375 1050);
PAINT GREEN (2375 1050);
DISPLAY INVISIBLE (2375 1050);
FORCEPROP 2 LAST CDS_LIB mstr_symbols
J 0
(2450 1100);
DISPLAY 0.787234 (2450 1100);
PAINT MONO (2450 1100);
DISPLAY INVISIBLE (2450 1100);
FORCEPROP 1 LAST BODY_TYPE PLUMBING
J 2
(2495 1057);
DISPLAY 0.340426 (2495 1057);
PAINT GREEN (2495 1057);
DISPLAY INVISIBLE (2495 1057);
FORCEPROP 1 LAST PATH I173
J 2
(2375 1100);
DISPLAY 1.404255 (2375 1100);
PAINT GREEN (2375 1100);
DISPLAY INVISIBLE (2375 1100);
FORCEPROP 2 LAST ROOM DDR4_CH_C
J 0
(2450 1105);
PAINT ORANGE (2450 1105);
DISPLAY INVISIBLE (2450 1105);
FORCEPROP 1 LAST HDL_POWER GND
J 2
(2450 1250);
DISPLAY 0.553191 (2450 1250);
PAINT GREEN (2450 1250);
DISPLAY INVISIBLE (2450 1250);
FORCEADD GND..1
R 2
(-5050 1475);
FORCEPROP 3 LASTPIN (-5050 1525) SIG_NAME GND\g
J 0
(-5040 1535);
DISPLAY 0.659574 (-5040 1535);
PAINT MONO (-5040 1535);
DISPLAY INVISIBLE (-5040 1535);
FORCEPROP 1 LAST VOLTAGE 0
J 0
(-5050 1475);
PAINT SKYBLUE (-5050 1475);
DISPLAY INVISIBLE (-5050 1475);
FORCEPROP 2 LAST BOM_COST MEM
J 0
(-5050 1480);
PAINT ORANGE (-5050 1480);
DISPLAY INVISIBLE (-5050 1480);
FORCEPROP 2 LAST CDS_LIB mstr_symbols
J 0
(-5050 1475);
DISPLAY 0.787234 (-5050 1475);
PAINT MONO (-5050 1475);
DISPLAY INVISIBLE (-5050 1475);
FORCEPROP 1 LAST SIZE 1B
J 2
(-5125 1425);
DISPLAY 1.170213 (-5125 1425);
PAINT GREEN (-5125 1425);
DISPLAY INVISIBLE (-5125 1425);
FORCEPROP 1 LAST BODY_TYPE PLUMBING
J 2
(-5005 1432);
DISPLAY 0.340426 (-5005 1432);
PAINT GREEN (-5005 1432);
DISPLAY INVISIBLE (-5005 1432);
FORCEPROP 1 LAST PATH I175
J 2
(-5125 1475);
DISPLAY 1.404255 (-5125 1475);
PAINT GREEN (-5125 1475);
DISPLAY INVISIBLE (-5125 1475);
FORCEPROP 2 LAST ROOM DDR4_CH_C
J 0
(-5050 1480);
PAINT ORANGE (-5050 1480);
DISPLAY INVISIBLE (-5050 1480);
FORCEPROP 1 LAST HDL_POWER GND
J 2
(-5050 1625);
DISPLAY 0.553191 (-5050 1625);
PAINT GREEN (-5050 1625);
DISPLAY INVISIBLE (-5050 1625);
FORCEADD OFFPAGE..5
(-4025 2125);
FORCEPROP 2 LAST $XR23 94 
J 0
(-4519 2161);
DISPLAY 0.638298 (-4519 2161);
PAINT MONO (-4519 2161);
FORCEPROP 2 LAST $XR22 88 
J 0
(-4429 2161);
DISPLAY 0.638298 (-4429 2161);
PAINT MONO (-4429 2161);
FORCEPROP 2 LAST $XR21 87 
J 0
(-4339 2161);
DISPLAY 0.638298 (-4339 2161);
PAINT MONO (-4339 2161);
FORCEPROP 2 LAST $XR20 86 
J 0
(-4249 2161);
DISPLAY 0.638298 (-4249 2161);
PAINT MONO (-4249 2161);
FORCEPROP 2 LAST $XR19 85 
J 0
(-5059 2089);
DISPLAY 0.638298 (-5059 2089);
PAINT MONO (-5059 2089);
FORCEPROP 2 LAST $XR18 84 
J 0
(-4969 2089);
DISPLAY 0.638298 (-4969 2089);
PAINT MONO (-4969 2089);
FORCEPROP 2 LAST $XR17 83 
J 0
(-4879 2089);
DISPLAY 0.638298 (-4879 2089);
PAINT MONO (-4879 2089);
FORCEPROP 2 LAST $XR16 82 
J 0
(-4789 2089);
DISPLAY 0.638298 (-4789 2089);
PAINT MONO (-4789 2089);
FORCEPROP 2 LAST $XR15 81 
J 0
(-4699 2089);
DISPLAY 0.638298 (-4699 2089);
PAINT MONO (-4699 2089);
FORCEPROP 2 LAST $XR14 80 
J 0
(-4609 2089);
DISPLAY 0.638298 (-4609 2089);
PAINT MONO (-4609 2089);
FORCEPROP 2 LAST $XR13 79 
J 0
(-4519 2089);
DISPLAY 0.638298 (-4519 2089);
PAINT MONO (-4519 2089);
FORCEPROP 2 LAST $XR12 78 
J 0
(-4429 2089);
DISPLAY 0.638298 (-4429 2089);
PAINT MONO (-4429 2089);
FORCEPROP 2 LAST $XR11 77 
J 0
(-4339 2089);
DISPLAY 0.638298 (-4339 2089);
PAINT MONO (-4339 2089);
FORCEPROP 2 LAST $XR10 54 
J 0
(-4249 2089);
DISPLAY 0.638298 (-4249 2089);
PAINT MONO (-4249 2089);
FORCEPROP 2 LAST $XR9 52 
J 0
(-5059 2125);
DISPLAY 0.638298 (-5059 2125);
PAINT MONO (-5059 2125);
FORCEPROP 2 LAST $XR8 51 
J 0
(-4969 2125);
DISPLAY 0.638298 (-4969 2125);
PAINT MONO (-4969 2125);
FORCEPROP 2 LAST $XR7 50 
J 0
(-4879 2125);
DISPLAY 0.638298 (-4879 2125);
PAINT MONO (-4879 2125);
FORCEPROP 2 LAST $XR6 49 
J 0
(-4789 2125);
DISPLAY 0.638298 (-4789 2125);
PAINT MONO (-4789 2125);
FORCEPROP 2 LAST $XR5 48 
J 0
(-4699 2125);
DISPLAY 0.638298 (-4699 2125);
PAINT MONO (-4699 2125);
FORCEPROP 2 LAST $XR4 47 
J 0
(-4609 2125);
DISPLAY 0.638298 (-4609 2125);
PAINT MONO (-4609 2125);
FORCEPROP 2 LAST $XR3 46 
J 0
(-4519 2125);
DISPLAY 0.638298 (-4519 2125);
PAINT MONO (-4519 2125);
FORCEPROP 2 LAST $XR2 45 
J 0
(-4429 2125);
DISPLAY 0.638298 (-4429 2125);
PAINT MONO (-4429 2125);
FORCEPROP 2 LAST $XR1 44 
J 0
(-4339 2125);
DISPLAY 0.638298 (-4339 2125);
PAINT MONO (-4339 2125);
FORCEPROP 2 LAST $XR0 43 
J 0
(-4249 2125);
DISPLAY 0.638298 (-4249 2125);
PAINT MONO (-4249 2125);
FORCEPROP 2 LAST CDS_LIB mstr_standard
J 0
(-4025 2125);
DISPLAY 0.787234 (-4025 2125);
PAINT MONO (-4025 2125);
DISPLAY INVISIBLE (-4025 2125);
FORCEPROP 1 LAST OFFPAGE TRUE
J 0
(-3700 2000);
DISPLAY 1.404255 (-3700 2000);
PAINT GREEN (-3700 2000);
DISPLAY INVISIBLE (-3700 2000);
FORCEPROP 1 LAST COMMENT_BODY TRUE
J 0
(-3925 2050);
DISPLAY 1.404255 (-3925 2050);
PAINT GREEN (-3925 2050);
DISPLAY INVISIBLE (-3925 2050);
FORCEPROP 2 LAST PATH I176
J 0
(-3975 2200);
DISPLAY 0.787234 (-3975 2200);
PAINT ORANGE (-3975 2200);
DISPLAY INVISIBLE (-3975 2200);
FORCEADD OFFPAGE..1
(-4650 1325);
FORCEPROP 2 LAST $XR1 54 
J 0
(-4991 1325);
DISPLAY 0.638298 (-4991 1325);
PAINT MONO (-4991 1325);
FORCEPROP 2 LAST $XR0 98 
J 0
(-4901 1325);
DISPLAY 0.638298 (-4901 1325);
PAINT MONO (-4901 1325);
FORCEPROP 2 LAST CDS_LIB mstr_standard
J 0
(-4650 1325);
DISPLAY 0.787234 (-4650 1325);
PAINT MONO (-4650 1325);
DISPLAY INVISIBLE (-4650 1325);
FORCEPROP 1 LAST OFFPAGE TRUE
J 0
(-4325 1200);
DISPLAY 0.936170 (-4325 1200);
PAINT GREEN (-4325 1200);
DISPLAY INVISIBLE (-4325 1200);
FORCEPROP 1 LAST COMMENT_BODY TRUE
J 0
(-4525 1225);
DISPLAY 0.936170 (-4525 1225);
PAINT GREEN (-4525 1225);
DISPLAY INVISIBLE (-4525 1225);
FORCEPROP 2 LAST PATH I177
J 0
(-4900 1375);
DISPLAY 0.787234 (-4900 1375);
PAINT ORANGE (-4900 1375);
DISPLAY INVISIBLE (-4900 1375);
FORCEADD CAP_A..1
R 2
(-4500 1125);
FORCEPROP 1 LAST LOCATION C6L1
J 2
(-4550 1225);
DISPLAY 0.617021 (-4550 1225);
PAINT AQUA (-4550 1225);
FORCEPROP 1 LAST PART_NUMBER A36096-045
J 2
(-4550 975);
DISPLAY 0.617021 (-4550 975);
PAINT BLUE (-4550 975);
FORCEPROP 1 LAST VALUE 0.01UF
J 2
(-4550 1175);
DISPLAY 0.617021 (-4550 1175);
PAINT SKYBLUE (-4550 1175);
FORCEPROP 1 LAST TOLERANCE 10%
J 2
(-4550 1075);
DISPLAY 0.617021 (-4550 1075);
PAINT SKYBLUE (-4550 1075);
FORCEPROP 1 LAST MATERIAL X7R
J 2
(-4550 1025);
DISPLAY 0.617021 (-4550 1025);
PAINT SKYBLUE (-4550 1025);
FORCEPROP 1 LAST VOLTAGE 25V
J 2
(-4550 1125);
DISPLAY 0.617021 (-4550 1125);
PAINT SKYBLUE (-4550 1125);
FORCEPROP 1 LAST PACK_TYPE 0402V
J 2
(-4550 925);
DISPLAY 0.617021 (-4550 925);
PAINT SKYBLUE (-4550 925);
FORCEPROP 1 LASTPIN (-4500 1025) $PN 2
J 2
(-4510 1005);
DISPLAY 0.787234 (-4510 1005);
PAINT ORANGE (-4510 1005);
FORCEPROP 1 LASTPIN (-4500 1225) $PN 1
J 2
(-4510 1205);
DISPLAY 0.787234 (-4510 1205);
PAINT ORANGE (-4510 1205);
FORCEPROP 2 LAST CDS_LOCATION C6L1
J 2
(-4550 1225);
DISPLAY 0.617021 (-4550 1225);
PAINT AQUA (-4550 1225);
DISPLAY INVISIBLE (-4550 1225);
FORCEPROP 2 LAST BOM_COST MEM
J 0
(-4500 1125);
PAINT ORANGE (-4500 1125);
DISPLAY INVISIBLE (-4500 1125);
FORCEPROP 2 LAST CDS_LIB dev_discrete
J 0
(-4500 1125);
PAINT ORANGE (-4500 1125);
DISPLAY INVISIBLE (-4500 1125);
FORCEPROP 1 LAST PATH I178
J 2
(-4550 1275);
DISPLAY 0.978723 (-4550 1275);
PAINT WHITE (-4550 1275);
DISPLAY INVISIBLE (-4550 1275);
FORCEPROP 2 LAST ROOM DDR4_CH_F
J 0
(-4500 1125);
PAINT ORANGE (-4500 1125);
DISPLAY INVISIBLE (-4500 1125);
FORCEPROP 2 LAST SEC 1
J 0
(-4550 1325);
PAINT MONO (-4550 1325);
DISPLAY INVISIBLE (-4550 1325);
FORCEPROP 2 LAST SEC_TYPE 0402V
J 0
(-4550 1325);
DISPLAY 1.021277 (-4550 1325);
PAINT ORANGE (-4550 1325);
DISPLAY INVISIBLE (-4550 1325);
FORCEADD GND..1
(-4500 875);
FORCEPROP 3 LASTPIN (-4500 925) SIG_NAME GND\g
J 0
(-4490 935);
DISPLAY 0.659574 (-4490 935);
PAINT MONO (-4490 935);
DISPLAY INVISIBLE (-4490 935);
FORCEPROP 1 LAST VOLTAGE 0
J 0
(-4500 875);
PAINT SKYBLUE (-4500 875);
DISPLAY INVISIBLE (-4500 875);
FORCEPROP 2 LAST BOM_COST MEM
J 0
(-4500 880);
PAINT ORANGE (-4500 880);
DISPLAY INVISIBLE (-4500 880);
FORCEPROP 1 LAST SIZE 1B
J 0
(-4425 825);
DISPLAY 1.787234 (-4425 825);
PAINT GREEN (-4425 825);
DISPLAY INVISIBLE (-4425 825);
FORCEPROP 2 LAST CDS_LIB mstr_symbols
J 0
(-4500 875);
PAINT ORANGE (-4500 875);
DISPLAY INVISIBLE (-4500 875);
FORCEPROP 1 LAST BODY_TYPE PLUMBING
J 0
(-4545 832);
DISPLAY 0.340426 (-4545 832);
PAINT GREEN (-4545 832);
DISPLAY INVISIBLE (-4545 832);
FORCEPROP 1 LAST PATH I179
J 0
(-4425 875);
DISPLAY 1.404255 (-4425 875);
PAINT GREEN (-4425 875);
DISPLAY INVISIBLE (-4425 875);
FORCEPROP 2 LAST ROOM DDR4_CH_C
J 0
(-4500 880);
PAINT ORANGE (-4500 880);
DISPLAY INVISIBLE (-4500 880);
FORCEPROP 1 LAST HDL_POWER GND
J 0
(-4500 1025);
DISPLAY 1.404255 (-4500 1025);
PAINT GREEN (-4500 1025);
DISPLAY INVISIBLE (-4500 1025);
FORCEADD PVPP_DEF..1
(-950 3050);
FORCEPROP 3 LASTPIN (-950 3000) SIG_NAME PVPP_DEF\g
J 0
(-940 3010);
DISPLAY 0.659574 (-940 3010);
PAINT MONO (-940 3010);
DISPLAY INVISIBLE (-940 3010);
FORCEPROP 1 LAST VOLTAGE 2.5V
J 0
(-995 3007);
DISPLAY 0.340426 (-995 3007);
PAINT SKYBLUE (-995 3007);
DISPLAY INVISIBLE (-995 3007);
FORCEPROP 0 LAST BOM_COST MEM
J 0
(-950 3150);
PAINT ORANGE (-950 3150);
DISPLAY INVISIBLE (-950 3150);
FORCEPROP 2 LAST CDS_LIB mstr_symbols
J 0
(-950 3050);
PAINT ORANGE (-950 3050);
DISPLAY INVISIBLE (-950 3050);
FORCEPROP 1 LAST BODY_TYPE PLUMBING
J 0
(-995 3007);
DISPLAY 0.340426 (-995 3007);
PAINT GREEN (-995 3007);
DISPLAY INVISIBLE (-995 3007);
FORCEPROP 1 LAST PATH I180
J 0
(-900 3075);
DISPLAY 0.872340 (-900 3075);
PAINT AQUA (-900 3075);
DISPLAY INVISIBLE (-900 3075);
FORCEPROP 2 LAST ROOM DDR4_CH_C
J 0
(-950 3150);
PAINT ORANGE (-950 3150);
DISPLAY INVISIBLE (-950 3150);
FORCEPROP 1 LAST HDL_POWER PVPP_DEF
J 1
(-950 3100);
DISPLAY 0.872340 (-950 3100);
PAINT GREEN (-950 3100);
DISPLAY INVISIBLE (-950 3100);
FORCEADD PVPP_DEF..1
(-5050 1825);
FORCEPROP 3 LASTPIN (-5050 1775) SIG_NAME PVPP_DEF\g
J 0
(-5040 1785);
DISPLAY 0.659574 (-5040 1785);
PAINT MONO (-5040 1785);
DISPLAY INVISIBLE (-5040 1785);
FORCEPROP 1 LAST VOLTAGE 2.5V
J 0
(-5095 1782);
DISPLAY 0.340426 (-5095 1782);
PAINT SKYBLUE (-5095 1782);
DISPLAY INVISIBLE (-5095 1782);
FORCEPROP 0 LAST BOM_COST MEM
J 0
(-5050 1925);
PAINT ORANGE (-5050 1925);
DISPLAY INVISIBLE (-5050 1925);
FORCEPROP 2 LAST CDS_LIB mstr_symbols
J 0
(-5050 1825);
PAINT ORANGE (-5050 1825);
DISPLAY INVISIBLE (-5050 1825);
FORCEPROP 1 LAST BODY_TYPE PLUMBING
J 0
(-5095 1782);
DISPLAY 0.340426 (-5095 1782);
PAINT GREEN (-5095 1782);
DISPLAY INVISIBLE (-5095 1782);
FORCEPROP 1 LAST PATH I181
J 0
(-5000 1850);
DISPLAY 0.872340 (-5000 1850);
PAINT AQUA (-5000 1850);
DISPLAY INVISIBLE (-5000 1850);
FORCEPROP 2 LAST ROOM DDR4_CH_C
J 0
(-5050 1925);
PAINT ORANGE (-5050 1925);
DISPLAY INVISIBLE (-5050 1925);
FORCEPROP 1 LAST HDL_POWER PVPP_DEF
J 1
(-5050 1875);
DISPLAY 0.872340 (-5050 1875);
PAINT GREEN (-5050 1875);
DISPLAY INVISIBLE (-5050 1875);
FORCEADD OFFPAGE..1
(-3700 1025);
FORCEPROP 2 LAST $XR5 54 
J 0
(-4371 1025);
DISPLAY 0.638298 (-4371 1025);
PAINT MONO (-4371 1025);
FORCEPROP 2 LAST $XR4 52 
J 0
(-4281 1025);
DISPLAY 0.638298 (-4281 1025);
PAINT MONO (-4281 1025);
FORCEPROP 2 LAST $XR3 51 
J 0
(-4191 1025);
DISPLAY 0.638298 (-4191 1025);
PAINT MONO (-4191 1025);
FORCEPROP 2 LAST $XR2 50 
J 0
(-4101 1025);
DISPLAY 0.638298 (-4101 1025);
PAINT MONO (-4101 1025);
FORCEPROP 2 LAST $XR1 49 
J 0
(-4011 1025);
DISPLAY 0.638298 (-4011 1025);
PAINT MONO (-4011 1025);
FORCEPROP 2 LAST $XR0 89 
J 0
(-3921 1025);
DISPLAY 0.638298 (-3921 1025);
PAINT MONO (-3921 1025);
FORCEPROP 2 LAST CDS_LIB mstr_standard
J 0
(-3700 1025);
PAINT ORANGE (-3700 1025);
DISPLAY INVISIBLE (-3700 1025);
FORCEPROP 1 LAST OFFPAGE TRUE
J 0
(-3375 900);
DISPLAY 0.936170 (-3375 900);
PAINT GREEN (-3375 900);
DISPLAY INVISIBLE (-3375 900);
FORCEPROP 1 LAST COMMENT_BODY TRUE
J 0
(-3575 925);
DISPLAY 0.936170 (-3575 925);
PAINT GREEN (-3575 925);
DISPLAY INVISIBLE (-3575 925);
FORCEPROP 2 LAST PATH I182
J 0
(-3650 1100);
PAINT ORANGE (-3650 1100);
DISPLAY INVISIBLE (-3650 1100);
FORCEADD TAP..6
R 2
(850 4550);
FORCEPROP 3 LASTPIN (800 4550) SIG_NAME M_F_DQS_DN<11>
J 0
(810 4560);
DISPLAY 0.659574 (810 4560);
PAINT MONO (810 4560);
DISPLAY INVISIBLE (810 4560);
FORCEPROP 1 LASTPIN (800 4550) BN 11
J 2
(850 4560);
DISPLAY 0.617021 (850 4560);
PAINT PINK (850 4560);
FORCEPROP 2 LAST CDS_LIB mstr_standard
J 0
(850 4550);
DISPLAY 0.787234 (850 4550);
PAINT MONO (850 4550);
DISPLAY INVISIBLE (850 4550);
FORCEPROP 1 LAST BODY_TYPE PLUMBING
J 2
(850 4500);
DISPLAY 1.234043 (850 4500);
PAINT GREEN (850 4500);
DISPLAY INVISIBLE (850 4500);
FORCEPROP 1 LAST HDL_TAP TRUE
J 2
(525 4425);
DISPLAY 1.234043 (525 4425);
PAINT GREEN (525 4425);
DISPLAY INVISIBLE (525 4425);
FORCEPROP 1 LAST PATH I19
J 2
(850 4550);
DISPLAY 0.936170 (850 4550);
PAINT GREEN (850 4550);
DISPLAY INVISIBLE (850 4550);
FORCEADD P12V_NVDIMM_DEF..1
(450 3125);
FORCEPROP 3 LASTPIN (450 3075) SIG_NAME P12V_NVDIMM_DEF\g
J 0
(460 3085);
DISPLAY 0.659574 (460 3085);
PAINT MONO (460 3085);
DISPLAY INVISIBLE (460 3085);
FORCEPROP 1 LAST VOLTAGE 12.0
J 0
(405 3082);
DISPLAY 0.340426 (405 3082);
PAINT SKYBLUE (405 3082);
DISPLAY INVISIBLE (405 3082);
FORCEPROP 2 LAST CDS_LIB mstr_symbols
J 0
(450 3125);
PAINT ORANGE (450 3125);
DISPLAY INVISIBLE (450 3125);
FORCEPROP 1 LAST BODY_TYPE PLUMBING
J 0
(405 3082);
DISPLAY 0.340426 (405 3082);
PAINT GREEN (405 3082);
DISPLAY INVISIBLE (405 3082);
FORCEPROP 1 LAST PATH I195
J 0
(500 3150);
DISPLAY 0.872340 (500 3150);
PAINT AQUA (500 3150);
DISPLAY INVISIBLE (500 3150);
FORCEPROP 1 LAST HDL_POWER P12V_NVDIMM_DEF
J 1
(450 3175);
DISPLAY 0.872340 (450 3175);
PAINT GREEN (450 3175);
DISPLAY INVISIBLE (450 3175);
FORCEADD OFFPAGE..3
(1550 5200);
FORCEPROP 2 LAST $XR1 54 
J 0
(1854 5200);
DISPLAY 0.638298 (1854 5200);
PAINT MONO (1854 5200);
FORCEPROP 2 LAST $XR0 28 
J 0
(1764 5200);
DISPLAY 0.638298 (1764 5200);
PAINT MONO (1764 5200);
FORCEPROP 2 LAST CDS_LIB mstr_standard
J 0
(1550 5200);
DISPLAY 0.787234 (1550 5200);
PAINT MONO (1550 5200);
DISPLAY INVISIBLE (1550 5200);
FORCEPROP 1 LAST OFFPAGE TRUE
J 0
(1875 5075);
DISPLAY 0.936170 (1875 5075);
PAINT GREEN (1875 5075);
DISPLAY INVISIBLE (1875 5075);
FORCEPROP 1 LAST COMMENT_BODY TRUE
J 0
(1500 5100);
DISPLAY 0.936170 (1500 5100);
PAINT GREEN (1500 5100);
DISPLAY INVISIBLE (1500 5100);
FORCEPROP 2 LAST PATH I2
J 0
(1750 5275);
DISPLAY 0.787234 (1750 5275);
PAINT MONO (1750 5275);
DISPLAY INVISIBLE (1750 5275);
FORCEADD TAP..6
R 2
(850 4450);
FORCEPROP 3 LASTPIN (800 4450) SIG_NAME M_F_DQS_DN<10>
J 0
(810 4460);
DISPLAY 0.659574 (810 4460);
PAINT MONO (810 4460);
DISPLAY INVISIBLE (810 4460);
FORCEPROP 1 LASTPIN (800 4450) BN 10
J 2
(850 4460);
DISPLAY 0.617021 (850 4460);
PAINT PINK (850 4460);
FORCEPROP 2 LAST CDS_LIB mstr_standard
J 0
(850 4450);
DISPLAY 0.787234 (850 4450);
PAINT MONO (850 4450);
DISPLAY INVISIBLE (850 4450);
FORCEPROP 1 LAST BODY_TYPE PLUMBING
J 2
(850 4400);
DISPLAY 1.234043 (850 4400);
PAINT GREEN (850 4400);
DISPLAY INVISIBLE (850 4400);
FORCEPROP 1 LAST HDL_TAP TRUE
J 2
(525 4325);
DISPLAY 1.234043 (525 4325);
PAINT GREEN (525 4325);
DISPLAY INVISIBLE (525 4325);
FORCEPROP 1 LAST PATH I20
J 2
(850 4450);
DISPLAY 0.936170 (850 4450);
PAINT GREEN (850 4450);
DISPLAY INVISIBLE (850 4450);
FORCEADD TAP..6
R 2
(850 4350);
FORCEPROP 3 LASTPIN (800 4350) SIG_NAME M_F_DQS_DN<9>
J 0
(810 4360);
DISPLAY 0.659574 (810 4360);
PAINT MONO (810 4360);
DISPLAY INVISIBLE (810 4360);
FORCEPROP 1 LASTPIN (800 4350) BN 9
J 2
(850 4360);
DISPLAY 0.617021 (850 4360);
PAINT PINK (850 4360);
FORCEPROP 2 LAST CDS_LIB mstr_standard
J 0
(850 4350);
DISPLAY 0.787234 (850 4350);
PAINT MONO (850 4350);
DISPLAY INVISIBLE (850 4350);
FORCEPROP 1 LAST BODY_TYPE PLUMBING
J 2
(850 4300);
DISPLAY 1.234043 (850 4300);
PAINT GREEN (850 4300);
DISPLAY INVISIBLE (850 4300);
FORCEPROP 1 LAST HDL_TAP TRUE
J 2
(525 4225);
DISPLAY 1.234043 (525 4225);
PAINT GREEN (525 4225);
DISPLAY INVISIBLE (525 4225);
FORCEPROP 1 LAST PATH I21
J 2
(850 4350);
DISPLAY 0.936170 (850 4350);
PAINT GREEN (850 4350);
DISPLAY INVISIBLE (850 4350);
FORCEADD TAP..6
R 2
(850 4250);
FORCEPROP 3 LASTPIN (800 4250) SIG_NAME M_F_DQS_DN<8>
J 0
(810 4260);
DISPLAY 0.659574 (810 4260);
PAINT MONO (810 4260);
DISPLAY INVISIBLE (810 4260);
FORCEPROP 1 LASTPIN (800 4250) BN 8
J 2
(850 4260);
DISPLAY 0.617021 (850 4260);
PAINT PINK (850 4260);
FORCEPROP 2 LAST CDS_LIB mstr_standard
J 0
(850 4250);
DISPLAY 0.787234 (850 4250);
PAINT MONO (850 4250);
DISPLAY INVISIBLE (850 4250);
FORCEPROP 1 LAST BODY_TYPE PLUMBING
J 2
(850 4200);
DISPLAY 1.234043 (850 4200);
PAINT GREEN (850 4200);
DISPLAY INVISIBLE (850 4200);
FORCEPROP 1 LAST HDL_TAP TRUE
J 2
(525 4125);
DISPLAY 1.234043 (525 4125);
PAINT GREEN (525 4125);
DISPLAY INVISIBLE (525 4125);
FORCEPROP 1 LAST PATH I22
J 2
(850 4250);
DISPLAY 0.936170 (850 4250);
PAINT GREEN (850 4250);
DISPLAY INVISIBLE (850 4250);
FORCEADD TAP..6
R 2
(850 4150);
FORCEPROP 3 LASTPIN (800 4150) SIG_NAME M_F_DQS_DN<7>
J 0
(810 4160);
DISPLAY 0.659574 (810 4160);
PAINT MONO (810 4160);
DISPLAY INVISIBLE (810 4160);
FORCEPROP 1 LASTPIN (800 4150) BN 7
J 2
(850 4160);
DISPLAY 0.617021 (850 4160);
PAINT PINK (850 4160);
FORCEPROP 2 LAST CDS_LIB mstr_standard
J 0
(850 4150);
DISPLAY 0.787234 (850 4150);
PAINT MONO (850 4150);
DISPLAY INVISIBLE (850 4150);
FORCEPROP 1 LAST BODY_TYPE PLUMBING
J 2
(850 4100);
DISPLAY 1.234043 (850 4100);
PAINT GREEN (850 4100);
DISPLAY INVISIBLE (850 4100);
FORCEPROP 1 LAST HDL_TAP TRUE
J 2
(525 4025);
DISPLAY 1.234043 (525 4025);
PAINT GREEN (525 4025);
DISPLAY INVISIBLE (525 4025);
FORCEPROP 1 LAST PATH I23
J 2
(850 4150);
DISPLAY 0.936170 (850 4150);
PAINT GREEN (850 4150);
DISPLAY INVISIBLE (850 4150);
FORCEADD TAP..6
R 2
(650 4400);
FORCEPROP 3 LASTPIN (600 4400) SIG_NAME M_F_DQS_DP<9>
J 0
(610 4410);
DISPLAY 0.659574 (610 4410);
PAINT MONO (610 4410);
DISPLAY INVISIBLE (610 4410);
FORCEPROP 1 LASTPIN (600 4400) BN 9
J 2
(650 4410);
DISPLAY 0.617021 (650 4410);
PAINT PINK (650 4410);
FORCEPROP 2 LAST CDS_LIB mstr_standard
J 0
(650 4400);
DISPLAY 0.787234 (650 4400);
PAINT MONO (650 4400);
DISPLAY INVISIBLE (650 4400);
FORCEPROP 1 LAST BODY_TYPE PLUMBING
J 2
(650 4350);
DISPLAY 1.234043 (650 4350);
PAINT GREEN (650 4350);
DISPLAY INVISIBLE (650 4350);
FORCEPROP 1 LAST HDL_TAP TRUE
J 2
(325 4275);
DISPLAY 1.234043 (325 4275);
PAINT GREEN (325 4275);
DISPLAY INVISIBLE (325 4275);
FORCEPROP 1 LAST PATH I24
J 2
(650 4400);
DISPLAY 0.936170 (650 4400);
PAINT GREEN (650 4400);
DISPLAY INVISIBLE (650 4400);
FORCEADD TAP..6
R 2
(650 4500);
FORCEPROP 3 LASTPIN (600 4500) SIG_NAME M_F_DQS_DP<10>
J 0
(610 4510);
DISPLAY 0.659574 (610 4510);
PAINT MONO (610 4510);
DISPLAY INVISIBLE (610 4510);
FORCEPROP 1 LASTPIN (600 4500) BN 10
J 2
(650 4510);
DISPLAY 0.617021 (650 4510);
PAINT PINK (650 4510);
FORCEPROP 2 LAST CDS_LIB mstr_standard
J 0
(650 4500);
DISPLAY 0.787234 (650 4500);
PAINT MONO (650 4500);
DISPLAY INVISIBLE (650 4500);
FORCEPROP 1 LAST BODY_TYPE PLUMBING
J 2
(650 4450);
DISPLAY 1.234043 (650 4450);
PAINT GREEN (650 4450);
DISPLAY INVISIBLE (650 4450);
FORCEPROP 1 LAST HDL_TAP TRUE
J 2
(325 4375);
DISPLAY 1.234043 (325 4375);
PAINT GREEN (325 4375);
DISPLAY INVISIBLE (325 4375);
FORCEPROP 1 LAST PATH I25
J 2
(650 4500);
DISPLAY 0.936170 (650 4500);
PAINT GREEN (650 4500);
DISPLAY INVISIBLE (650 4500);
FORCEADD TAP..6
R 2
(650 4300);
FORCEPROP 3 LASTPIN (600 4300) SIG_NAME M_F_DQS_DP<8>
J 0
(610 4310);
DISPLAY 0.659574 (610 4310);
PAINT MONO (610 4310);
DISPLAY INVISIBLE (610 4310);
FORCEPROP 1 LASTPIN (600 4300) BN 8
J 2
(650 4310);
DISPLAY 0.617021 (650 4310);
PAINT PINK (650 4310);
FORCEPROP 2 LAST CDS_LIB mstr_standard
J 0
(650 4300);
DISPLAY 0.787234 (650 4300);
PAINT MONO (650 4300);
DISPLAY INVISIBLE (650 4300);
FORCEPROP 1 LAST BODY_TYPE PLUMBING
J 2
(650 4250);
DISPLAY 1.234043 (650 4250);
PAINT GREEN (650 4250);
DISPLAY INVISIBLE (650 4250);
FORCEPROP 1 LAST HDL_TAP TRUE
J 2
(325 4175);
DISPLAY 1.234043 (325 4175);
PAINT GREEN (325 4175);
DISPLAY INVISIBLE (325 4175);
FORCEPROP 1 LAST PATH I26
J 2
(650 4300);
DISPLAY 0.936170 (650 4300);
PAINT GREEN (650 4300);
DISPLAY INVISIBLE (650 4300);
FORCEADD TAP..6
R 2
(650 4100);
FORCEPROP 3 LASTPIN (600 4100) SIG_NAME M_F_DQS_DP<6>
J 0
(610 4110);
DISPLAY 0.659574 (610 4110);
PAINT MONO (610 4110);
DISPLAY INVISIBLE (610 4110);
FORCEPROP 1 LASTPIN (600 4100) BN 6
J 2
(650 4110);
DISPLAY 0.617021 (650 4110);
PAINT PINK (650 4110);
FORCEPROP 2 LAST CDS_LIB mstr_standard
J 0
(650 4100);
DISPLAY 0.787234 (650 4100);
PAINT MONO (650 4100);
DISPLAY INVISIBLE (650 4100);
FORCEPROP 1 LAST BODY_TYPE PLUMBING
J 2
(650 4050);
DISPLAY 1.234043 (650 4050);
PAINT GREEN (650 4050);
DISPLAY INVISIBLE (650 4050);
FORCEPROP 1 LAST HDL_TAP TRUE
J 2
(325 3975);
DISPLAY 1.234043 (325 3975);
PAINT GREEN (325 3975);
DISPLAY INVISIBLE (325 3975);
FORCEPROP 1 LAST PATH I27
J 2
(650 4100);
DISPLAY 0.936170 (650 4100);
PAINT GREEN (650 4100);
DISPLAY INVISIBLE (650 4100);
FORCEADD TAP..6
R 2
(650 4200);
FORCEPROP 3 LASTPIN (600 4200) SIG_NAME M_F_DQS_DP<7>
J 0
(610 4210);
DISPLAY 0.659574 (610 4210);
PAINT MONO (610 4210);
DISPLAY INVISIBLE (610 4210);
FORCEPROP 1 LASTPIN (600 4200) BN 7
J 2
(650 4210);
DISPLAY 0.617021 (650 4210);
PAINT PINK (650 4210);
FORCEPROP 2 LAST CDS_LIB mstr_standard
J 0
(650 4200);
DISPLAY 0.787234 (650 4200);
PAINT MONO (650 4200);
DISPLAY INVISIBLE (650 4200);
FORCEPROP 1 LAST BODY_TYPE PLUMBING
J 2
(650 4150);
DISPLAY 1.234043 (650 4150);
PAINT GREEN (650 4150);
DISPLAY INVISIBLE (650 4150);
FORCEPROP 1 LAST HDL_TAP TRUE
J 2
(325 4075);
DISPLAY 1.234043 (325 4075);
PAINT GREEN (325 4075);
DISPLAY INVISIBLE (325 4075);
FORCEPROP 1 LAST PATH I28
J 2
(650 4200);
DISPLAY 0.936170 (650 4200);
PAINT GREEN (650 4200);
DISPLAY INVISIBLE (650 4200);
FORCEADD TAP..6
R 2
(850 4050);
FORCEPROP 3 LASTPIN (800 4050) SIG_NAME M_F_DQS_DN<6>
J 0
(810 4060);
DISPLAY 0.659574 (810 4060);
PAINT MONO (810 4060);
DISPLAY INVISIBLE (810 4060);
FORCEPROP 1 LASTPIN (800 4050) BN 6
J 2
(850 4060);
DISPLAY 0.617021 (850 4060);
PAINT PINK (850 4060);
FORCEPROP 2 LAST CDS_LIB mstr_standard
J 0
(850 4050);
DISPLAY 0.787234 (850 4050);
PAINT MONO (850 4050);
DISPLAY INVISIBLE (850 4050);
FORCEPROP 1 LAST BODY_TYPE PLUMBING
J 2
(850 4000);
DISPLAY 1.234043 (850 4000);
PAINT GREEN (850 4000);
DISPLAY INVISIBLE (850 4000);
FORCEPROP 1 LAST HDL_TAP TRUE
J 2
(525 3925);
DISPLAY 1.234043 (525 3925);
PAINT GREEN (525 3925);
DISPLAY INVISIBLE (525 3925);
FORCEPROP 1 LAST PATH I29
J 2
(850 4050);
DISPLAY 0.936170 (850 4050);
PAINT GREEN (850 4050);
DISPLAY INVISIBLE (850 4050);
FORCEADD TAP..6
R 2
(850 5150);
FORCEPROP 3 LASTPIN (800 5150) SIG_NAME M_F_DQS_DN<17>
J 0
(810 5160);
DISPLAY 0.659574 (810 5160);
PAINT MONO (810 5160);
DISPLAY INVISIBLE (810 5160);
FORCEPROP 1 LASTPIN (800 5150) BN 17
J 2
(850 5160);
DISPLAY 0.617021 (850 5160);
PAINT PINK (850 5160);
FORCEPROP 2 LAST CDS_LIB mstr_standard
J 2
(850 5150);
DISPLAY 0.787234 (850 5150);
PAINT MONO (850 5150);
DISPLAY INVISIBLE (850 5150);
FORCEPROP 1 LAST BODY_TYPE PLUMBING
J 2
(850 5100);
DISPLAY 1.234043 (850 5100);
PAINT GREEN (850 5100);
DISPLAY INVISIBLE (850 5100);
FORCEPROP 1 LAST HDL_TAP TRUE
J 2
(525 5025);
DISPLAY 1.234043 (525 5025);
PAINT GREEN (525 5025);
DISPLAY INVISIBLE (525 5025);
FORCEPROP 1 LAST PATH I3
J 2
(850 5150);
DISPLAY 0.936170 (850 5150);
PAINT GREEN (850 5150);
DISPLAY INVISIBLE (850 5150);
FORCEADD TAP..6
R 2
(850 3950);
FORCEPROP 3 LASTPIN (800 3950) SIG_NAME M_F_DQS_DN<5>
J 0
(810 3960);
DISPLAY 0.659574 (810 3960);
PAINT MONO (810 3960);
DISPLAY INVISIBLE (810 3960);
FORCEPROP 1 LASTPIN (800 3950) BN 5
J 2
(850 3960);
DISPLAY 0.617021 (850 3960);
PAINT PINK (850 3960);
FORCEPROP 2 LAST CDS_LIB mstr_standard
J 0
(850 3950);
DISPLAY 0.787234 (850 3950);
PAINT MONO (850 3950);
DISPLAY INVISIBLE (850 3950);
FORCEPROP 1 LAST BODY_TYPE PLUMBING
J 2
(850 3900);
DISPLAY 1.234043 (850 3900);
PAINT GREEN (850 3900);
DISPLAY INVISIBLE (850 3900);
FORCEPROP 1 LAST HDL_TAP TRUE
J 2
(525 3825);
DISPLAY 1.234043 (525 3825);
PAINT GREEN (525 3825);
DISPLAY INVISIBLE (525 3825);
FORCEPROP 1 LAST PATH I30
J 2
(850 3950);
DISPLAY 0.936170 (850 3950);
PAINT GREEN (850 3950);
DISPLAY INVISIBLE (850 3950);
FORCEADD TAP..6
R 2
(850 3850);
FORCEPROP 3 LASTPIN (800 3850) SIG_NAME M_F_DQS_DN<4>
J 0
(810 3860);
DISPLAY 0.659574 (810 3860);
PAINT MONO (810 3860);
DISPLAY INVISIBLE (810 3860);
FORCEPROP 1 LASTPIN (800 3850) BN 4
J 2
(850 3860);
DISPLAY 0.617021 (850 3860);
PAINT PINK (850 3860);
FORCEPROP 2 LAST CDS_LIB mstr_standard
J 0
(850 3850);
DISPLAY 0.787234 (850 3850);
PAINT MONO (850 3850);
DISPLAY INVISIBLE (850 3850);
FORCEPROP 1 LAST BODY_TYPE PLUMBING
J 2
(850 3800);
DISPLAY 1.234043 (850 3800);
PAINT GREEN (850 3800);
DISPLAY INVISIBLE (850 3800);
FORCEPROP 1 LAST HDL_TAP TRUE
J 2
(525 3725);
DISPLAY 1.234043 (525 3725);
PAINT GREEN (525 3725);
DISPLAY INVISIBLE (525 3725);
FORCEPROP 1 LAST PATH I31
J 2
(850 3850);
DISPLAY 0.936170 (850 3850);
PAINT GREEN (850 3850);
DISPLAY INVISIBLE (850 3850);
FORCEADD TAP..6
R 2
(850 3750);
FORCEPROP 3 LASTPIN (800 3750) SIG_NAME M_F_DQS_DN<3>
J 0
(810 3760);
DISPLAY 0.659574 (810 3760);
PAINT MONO (810 3760);
DISPLAY INVISIBLE (810 3760);
FORCEPROP 1 LASTPIN (800 3750) BN 3
J 2
(850 3760);
DISPLAY 0.617021 (850 3760);
PAINT PINK (850 3760);
FORCEPROP 2 LAST CDS_LIB mstr_standard
J 0
(850 3750);
DISPLAY 0.787234 (850 3750);
PAINT MONO (850 3750);
DISPLAY INVISIBLE (850 3750);
FORCEPROP 1 LAST BODY_TYPE PLUMBING
J 2
(850 3700);
DISPLAY 1.234043 (850 3700);
PAINT GREEN (850 3700);
DISPLAY INVISIBLE (850 3700);
FORCEPROP 1 LAST HDL_TAP TRUE
J 2
(525 3625);
DISPLAY 1.234043 (525 3625);
PAINT GREEN (525 3625);
DISPLAY INVISIBLE (525 3625);
FORCEPROP 1 LAST PATH I32
J 2
(850 3750);
DISPLAY 0.936170 (850 3750);
PAINT GREEN (850 3750);
DISPLAY INVISIBLE (850 3750);
FORCEADD TAP..6
R 2
(850 3650);
FORCEPROP 3 LASTPIN (800 3650) SIG_NAME M_F_DQS_DN<2>
J 0
(810 3660);
DISPLAY 0.659574 (810 3660);
PAINT MONO (810 3660);
DISPLAY INVISIBLE (810 3660);
FORCEPROP 1 LASTPIN (800 3650) BN 2
J 2
(850 3660);
DISPLAY 0.617021 (850 3660);
PAINT PINK (850 3660);
FORCEPROP 2 LAST CDS_LIB mstr_standard
J 0
(850 3650);
DISPLAY 0.787234 (850 3650);
PAINT MONO (850 3650);
DISPLAY INVISIBLE (850 3650);
FORCEPROP 1 LAST BODY_TYPE PLUMBING
J 2
(850 3600);
DISPLAY 1.234043 (850 3600);
PAINT GREEN (850 3600);
DISPLAY INVISIBLE (850 3600);
FORCEPROP 1 LAST HDL_TAP TRUE
J 2
(525 3525);
DISPLAY 1.234043 (525 3525);
PAINT GREEN (525 3525);
DISPLAY INVISIBLE (525 3525);
FORCEPROP 1 LAST PATH I33
J 2
(850 3650);
DISPLAY 0.936170 (850 3650);
PAINT GREEN (850 3650);
DISPLAY INVISIBLE (850 3650);
FORCEADD TAP..6
R 2
(650 3900);
FORCEPROP 3 LASTPIN (600 3900) SIG_NAME M_F_DQS_DP<4>
J 0
(610 3910);
DISPLAY 0.659574 (610 3910);
PAINT MONO (610 3910);
DISPLAY INVISIBLE (610 3910);
FORCEPROP 1 LASTPIN (600 3900) BN 4
J 2
(650 3910);
DISPLAY 0.617021 (650 3910);
PAINT PINK (650 3910);
FORCEPROP 2 LAST CDS_LIB mstr_standard
J 0
(650 3900);
DISPLAY 0.787234 (650 3900);
PAINT MONO (650 3900);
DISPLAY INVISIBLE (650 3900);
FORCEPROP 1 LAST BODY_TYPE PLUMBING
J 2
(650 3850);
DISPLAY 1.234043 (650 3850);
PAINT GREEN (650 3850);
DISPLAY INVISIBLE (650 3850);
FORCEPROP 1 LAST HDL_TAP TRUE
J 2
(325 3775);
DISPLAY 1.234043 (325 3775);
PAINT GREEN (325 3775);
DISPLAY INVISIBLE (325 3775);
FORCEPROP 1 LAST PATH I34
J 2
(650 3900);
DISPLAY 0.936170 (650 3900);
PAINT GREEN (650 3900);
DISPLAY INVISIBLE (650 3900);
FORCEADD TAP..6
R 2
(650 4000);
FORCEPROP 3 LASTPIN (600 4000) SIG_NAME M_F_DQS_DP<5>
J 0
(610 4010);
DISPLAY 0.659574 (610 4010);
PAINT MONO (610 4010);
DISPLAY INVISIBLE (610 4010);
FORCEPROP 1 LASTPIN (600 4000) BN 5
J 2
(650 4010);
DISPLAY 0.617021 (650 4010);
PAINT PINK (650 4010);
FORCEPROP 2 LAST CDS_LIB mstr_standard
J 0
(650 4000);
DISPLAY 0.787234 (650 4000);
PAINT MONO (650 4000);
DISPLAY INVISIBLE (650 4000);
FORCEPROP 1 LAST BODY_TYPE PLUMBING
J 2
(650 3950);
DISPLAY 1.234043 (650 3950);
PAINT GREEN (650 3950);
DISPLAY INVISIBLE (650 3950);
FORCEPROP 1 LAST HDL_TAP TRUE
J 2
(325 3875);
DISPLAY 1.234043 (325 3875);
PAINT GREEN (325 3875);
DISPLAY INVISIBLE (325 3875);
FORCEPROP 1 LAST PATH I35
J 2
(650 4000);
DISPLAY 0.936170 (650 4000);
PAINT GREEN (650 4000);
DISPLAY INVISIBLE (650 4000);
FORCEADD TAP..6
R 2
(650 3800);
FORCEPROP 3 LASTPIN (600 3800) SIG_NAME M_F_DQS_DP<3>
J 0
(610 3810);
DISPLAY 0.659574 (610 3810);
PAINT MONO (610 3810);
DISPLAY INVISIBLE (610 3810);
FORCEPROP 1 LASTPIN (600 3800) BN 3
J 2
(650 3810);
DISPLAY 0.617021 (650 3810);
PAINT PINK (650 3810);
FORCEPROP 2 LAST CDS_LIB mstr_standard
J 0
(650 3800);
DISPLAY 0.787234 (650 3800);
PAINT MONO (650 3800);
DISPLAY INVISIBLE (650 3800);
FORCEPROP 1 LAST BODY_TYPE PLUMBING
J 2
(650 3750);
DISPLAY 1.234043 (650 3750);
PAINT GREEN (650 3750);
DISPLAY INVISIBLE (650 3750);
FORCEPROP 1 LAST HDL_TAP TRUE
J 2
(325 3675);
DISPLAY 1.234043 (325 3675);
PAINT GREEN (325 3675);
DISPLAY INVISIBLE (325 3675);
FORCEPROP 1 LAST PATH I36
J 2
(650 3800);
DISPLAY 0.936170 (650 3800);
PAINT GREEN (650 3800);
DISPLAY INVISIBLE (650 3800);
FORCEADD TAP..6
R 2
(650 3700);
FORCEPROP 3 LASTPIN (600 3700) SIG_NAME M_F_DQS_DP<2>
J 0
(610 3710);
DISPLAY 0.659574 (610 3710);
PAINT MONO (610 3710);
DISPLAY INVISIBLE (610 3710);
FORCEPROP 1 LASTPIN (600 3700) BN 2
J 2
(650 3710);
DISPLAY 0.617021 (650 3710);
PAINT PINK (650 3710);
FORCEPROP 2 LAST CDS_LIB mstr_standard
J 0
(650 3700);
DISPLAY 0.787234 (650 3700);
PAINT MONO (650 3700);
DISPLAY INVISIBLE (650 3700);
FORCEPROP 1 LAST BODY_TYPE PLUMBING
J 2
(650 3650);
DISPLAY 1.234043 (650 3650);
PAINT GREEN (650 3650);
DISPLAY INVISIBLE (650 3650);
FORCEPROP 1 LAST HDL_TAP TRUE
J 2
(325 3575);
DISPLAY 1.234043 (325 3575);
PAINT GREEN (325 3575);
DISPLAY INVISIBLE (325 3575);
FORCEPROP 1 LAST PATH I37
J 2
(650 3700);
DISPLAY 0.936170 (650 3700);
PAINT GREEN (650 3700);
DISPLAY INVISIBLE (650 3700);
FORCEADD TAP..6
R 2
(650 3600);
FORCEPROP 3 LASTPIN (600 3600) SIG_NAME M_F_DQS_DP<1>
J 0
(610 3610);
DISPLAY 0.659574 (610 3610);
PAINT MONO (610 3610);
DISPLAY INVISIBLE (610 3610);
FORCEPROP 1 LASTPIN (600 3600) BN 1
J 2
(650 3610);
DISPLAY 0.617021 (650 3610);
PAINT PINK (650 3610);
FORCEPROP 2 LAST CDS_LIB mstr_standard
J 0
(650 3600);
DISPLAY 0.787234 (650 3600);
PAINT MONO (650 3600);
DISPLAY INVISIBLE (650 3600);
FORCEPROP 1 LAST BODY_TYPE PLUMBING
J 2
(650 3550);
DISPLAY 1.234043 (650 3550);
PAINT GREEN (650 3550);
DISPLAY INVISIBLE (650 3550);
FORCEPROP 1 LAST HDL_TAP TRUE
J 2
(325 3475);
DISPLAY 1.234043 (325 3475);
PAINT GREEN (325 3475);
DISPLAY INVISIBLE (325 3475);
FORCEPROP 1 LAST PATH I38
J 2
(650 3600);
DISPLAY 0.936170 (650 3600);
PAINT GREEN (650 3600);
DISPLAY INVISIBLE (650 3600);
FORCEADD TAP..6
R 2
(850 3450);
FORCEPROP 3 LASTPIN (800 3450) SIG_NAME M_F_DQS_DN<0>
J 0
(810 3460);
DISPLAY 0.659574 (810 3460);
PAINT MONO (810 3460);
DISPLAY INVISIBLE (810 3460);
FORCEPROP 1 LASTPIN (800 3450) BN 0
J 2
(850 3460);
DISPLAY 0.617021 (850 3460);
PAINT PINK (850 3460);
FORCEPROP 2 LAST CDS_LIB mstr_standard
J 0
(850 3450);
DISPLAY 0.787234 (850 3450);
PAINT MONO (850 3450);
DISPLAY INVISIBLE (850 3450);
FORCEPROP 1 LAST BODY_TYPE PLUMBING
J 2
(850 3400);
DISPLAY 1.234043 (850 3400);
PAINT GREEN (850 3400);
DISPLAY INVISIBLE (850 3400);
FORCEPROP 1 LAST HDL_TAP TRUE
J 2
(525 3325);
DISPLAY 1.234043 (525 3325);
PAINT GREEN (525 3325);
DISPLAY INVISIBLE (525 3325);
FORCEPROP 1 LAST PATH I39
J 2
(850 3450);
DISPLAY 0.936170 (850 3450);
PAINT GREEN (850 3450);
DISPLAY INVISIBLE (850 3450);
FORCEADD TAP..6
R 2
(650 5200);
FORCEPROP 3 LASTPIN (600 5200) SIG_NAME M_F_DQS_DP<17>
J 0
(610 5210);
DISPLAY 0.659574 (610 5210);
PAINT MONO (610 5210);
DISPLAY INVISIBLE (610 5210);
FORCEPROP 1 LASTPIN (600 5200) BN 17
J 2
(650 5210);
DISPLAY 0.617021 (650 5210);
PAINT PINK (650 5210);
FORCEPROP 2 LAST CDS_LIB mstr_standard
J 2
(650 5200);
DISPLAY 0.787234 (650 5200);
PAINT MONO (650 5200);
DISPLAY INVISIBLE (650 5200);
FORCEPROP 1 LAST BODY_TYPE PLUMBING
J 2
(650 5150);
DISPLAY 1.234043 (650 5150);
PAINT GREEN (650 5150);
DISPLAY INVISIBLE (650 5150);
FORCEPROP 1 LAST HDL_TAP TRUE
J 2
(325 5075);
DISPLAY 1.234043 (325 5075);
PAINT GREEN (325 5075);
DISPLAY INVISIBLE (325 5075);
FORCEPROP 1 LAST PATH I4
J 2
(650 5200);
DISPLAY 0.936170 (650 5200);
PAINT GREEN (650 5200);
DISPLAY INVISIBLE (650 5200);
FORCEADD TAP..6
R 2
(850 3550);
FORCEPROP 3 LASTPIN (800 3550) SIG_NAME M_F_DQS_DN<1>
J 0
(810 3560);
DISPLAY 0.659574 (810 3560);
PAINT MONO (810 3560);
DISPLAY INVISIBLE (810 3560);
FORCEPROP 1 LASTPIN (800 3550) BN 1
J 2
(850 3560);
DISPLAY 0.617021 (850 3560);
PAINT PINK (850 3560);
FORCEPROP 2 LAST CDS_LIB mstr_standard
J 0
(850 3550);
DISPLAY 0.787234 (850 3550);
PAINT MONO (850 3550);
DISPLAY INVISIBLE (850 3550);
FORCEPROP 1 LAST BODY_TYPE PLUMBING
J 2
(850 3500);
DISPLAY 1.234043 (850 3500);
PAINT GREEN (850 3500);
DISPLAY INVISIBLE (850 3500);
FORCEPROP 1 LAST HDL_TAP TRUE
J 2
(525 3425);
DISPLAY 1.234043 (525 3425);
PAINT GREEN (525 3425);
DISPLAY INVISIBLE (525 3425);
FORCEPROP 1 LAST PATH I40
J 2
(850 3550);
DISPLAY 0.936170 (850 3550);
PAINT GREEN (850 3550);
DISPLAY INVISIBLE (850 3550);
FORCEADD TAP..6
R 2
(650 3500);
FORCEPROP 3 LASTPIN (600 3500) SIG_NAME M_F_DQS_DP<0>
J 0
(610 3510);
DISPLAY 0.659574 (610 3510);
PAINT MONO (610 3510);
DISPLAY INVISIBLE (610 3510);
FORCEPROP 1 LASTPIN (600 3500) BN 0
J 2
(650 3510);
DISPLAY 0.617021 (650 3510);
PAINT PINK (650 3510);
FORCEPROP 2 LAST CDS_LIB mstr_standard
J 0
(650 3500);
DISPLAY 0.787234 (650 3500);
PAINT MONO (650 3500);
DISPLAY INVISIBLE (650 3500);
FORCEPROP 1 LAST BODY_TYPE PLUMBING
J 2
(650 3450);
DISPLAY 1.234043 (650 3450);
PAINT GREEN (650 3450);
DISPLAY INVISIBLE (650 3450);
FORCEPROP 1 LAST HDL_TAP TRUE
J 2
(325 3375);
DISPLAY 1.234043 (325 3375);
PAINT GREEN (325 3375);
DISPLAY INVISIBLE (325 3375);
FORCEPROP 1 LAST PATH I41
J 2
(650 3500);
DISPLAY 0.936170 (650 3500);
PAINT GREEN (650 3500);
DISPLAY INVISIBLE (650 3500);
FORCEADD SCONN288_H44441004..3
(1750 2400);
FORCEPROP 1 LAST LOCATION J4A1
J 0
(1300 3800);
DISPLAY 0.617021 (1300 3800);
PAINT AQUA (1300 3800);
FORCEPROP 1 LAST PART_NUMBER H44441-004
J 0
(1300 1050);
DISPLAY 0.617021 (1300 1050);
PAINT BLUE (1300 1050);
FORCEPROP 1 LAST MATERIAL SCONN
J 0
(1300 3750);
DISPLAY 0.617021 (1300 3750);
PAINT SKYBLUE (1300 3750);
FORCEPROP 2 LASTPIN (1250 3550) $PN 2
J 2
(1240 3560);
DISPLAY 0.617021 (1240 3560);
PAINT ORANGE (1240 3560);
FORCEPROP 2 LASTPIN (1250 3500) $PN 4
J 2
(1240 3510);
DISPLAY 0.617021 (1240 3510);
PAINT ORANGE (1240 3510);
FORCEPROP 2 LASTPIN (1250 3450) $PN 6
J 2
(1240 3460);
DISPLAY 0.617021 (1240 3460);
PAINT ORANGE (1240 3460);
FORCEPROP 2 LASTPIN (1250 3400) $PN 9
J 2
(1240 3410);
DISPLAY 0.617021 (1240 3410);
PAINT ORANGE (1240 3410);
FORCEPROP 2 LASTPIN (1250 3350) $PN 11
J 2
(1240 3360);
DISPLAY 0.617021 (1240 3360);
PAINT ORANGE (1240 3360);
FORCEPROP 2 LASTPIN (1250 3300) $PN 13
J 2
(1240 3310);
DISPLAY 0.617021 (1240 3310);
PAINT ORANGE (1240 3310);
FORCEPROP 2 LASTPIN (1250 3250) $PN 15
J 2
(1240 3260);
DISPLAY 0.617021 (1240 3260);
PAINT ORANGE (1240 3260);
FORCEPROP 2 LASTPIN (1250 3200) $PN 17
J 2
(1240 3210);
DISPLAY 0.617021 (1240 3210);
PAINT ORANGE (1240 3210);
FORCEPROP 2 LASTPIN (1250 3150) $PN 20
J 2
(1240 3160);
DISPLAY 0.617021 (1240 3160);
PAINT ORANGE (1240 3160);
FORCEPROP 2 LASTPIN (1250 3100) $PN 22
J 2
(1240 3110);
DISPLAY 0.617021 (1240 3110);
PAINT ORANGE (1240 3110);
FORCEPROP 2 LASTPIN (1250 3050) $PN 24
J 2
(1240 3060);
DISPLAY 0.617021 (1240 3060);
PAINT ORANGE (1240 3060);
FORCEPROP 2 LASTPIN (1250 3000) $PN 26
J 2
(1240 3010);
DISPLAY 0.617021 (1240 3010);
PAINT ORANGE (1240 3010);
FORCEPROP 2 LASTPIN (1250 2950) $PN 28
J 2
(1240 2960);
DISPLAY 0.617021 (1240 2960);
PAINT ORANGE (1240 2960);
FORCEPROP 2 LASTPIN (1250 2900) $PN 31
J 2
(1240 2910);
DISPLAY 0.617021 (1240 2910);
PAINT ORANGE (1240 2910);
FORCEPROP 2 LASTPIN (1250 2850) $PN 33
J 2
(1240 2860);
DISPLAY 0.617021 (1240 2860);
PAINT ORANGE (1240 2860);
FORCEPROP 2 LASTPIN (1250 2800) $PN 35
J 2
(1240 2810);
DISPLAY 0.617021 (1240 2810);
PAINT ORANGE (1240 2810);
FORCEPROP 2 LASTPIN (1250 2750) $PN 37
J 2
(1240 2760);
DISPLAY 0.617021 (1240 2760);
PAINT ORANGE (1240 2760);
FORCEPROP 2 LASTPIN (1250 2700) $PN 39
J 2
(1240 2710);
DISPLAY 0.617021 (1240 2710);
PAINT ORANGE (1240 2710);
FORCEPROP 2 LASTPIN (1250 2650) $PN 42
J 2
(1240 2660);
DISPLAY 0.617021 (1240 2660);
PAINT ORANGE (1240 2660);
FORCEPROP 2 LASTPIN (1250 2600) $PN 44
J 2
(1240 2610);
DISPLAY 0.617021 (1240 2610);
PAINT ORANGE (1240 2610);
FORCEPROP 2 LASTPIN (1250 2550) $PN 46
J 2
(1240 2560);
DISPLAY 0.617021 (1240 2560);
PAINT ORANGE (1240 2560);
FORCEPROP 2 LASTPIN (1250 2500) $PN 48
J 2
(1240 2510);
DISPLAY 0.617021 (1240 2510);
PAINT ORANGE (1240 2510);
FORCEPROP 2 LASTPIN (1250 2450) $PN 50
J 2
(1240 2460);
DISPLAY 0.617021 (1240 2460);
PAINT ORANGE (1240 2460);
FORCEPROP 2 LASTPIN (1250 2400) $PN 53
J 2
(1240 2410);
DISPLAY 0.617021 (1240 2410);
PAINT ORANGE (1240 2410);
FORCEPROP 2 LASTPIN (1250 2350) $PN 55
J 2
(1240 2360);
DISPLAY 0.617021 (1240 2360);
PAINT ORANGE (1240 2360);
FORCEPROP 2 LASTPIN (1250 2300) $PN 57
J 2
(1240 2310);
DISPLAY 0.617021 (1240 2310);
PAINT ORANGE (1240 2310);
FORCEPROP 2 LASTPIN (1250 2250) $PN 94
J 2
(1240 2260);
DISPLAY 0.617021 (1240 2260);
PAINT ORANGE (1240 2260);
FORCEPROP 2 LASTPIN (1250 2200) $PN 96
J 2
(1240 2210);
DISPLAY 0.617021 (1240 2210);
PAINT ORANGE (1240 2210);
FORCEPROP 2 LASTPIN (1250 2150) $PN 98
J 2
(1240 2160);
DISPLAY 0.617021 (1240 2160);
PAINT ORANGE (1240 2160);
FORCEPROP 2 LASTPIN (1250 2100) $PN 101
J 2
(1240 2110);
DISPLAY 0.617021 (1240 2110);
PAINT ORANGE (1240 2110);
FORCEPROP 2 LASTPIN (1250 2050) $PN 103
J 2
(1240 2060);
DISPLAY 0.617021 (1240 2060);
PAINT ORANGE (1240 2060);
FORCEPROP 2 LASTPIN (1250 2000) $PN 105
J 2
(1240 2010);
DISPLAY 0.617021 (1240 2010);
PAINT ORANGE (1240 2010);
FORCEPROP 2 LASTPIN (1250 1950) $PN 107
J 2
(1240 1960);
DISPLAY 0.617021 (1240 1960);
PAINT ORANGE (1240 1960);
FORCEPROP 2 LASTPIN (1250 1900) $PN 109
J 2
(1240 1910);
DISPLAY 0.617021 (1240 1910);
PAINT ORANGE (1240 1910);
FORCEPROP 2 LASTPIN (1250 1850) $PN 112
J 2
(1240 1860);
DISPLAY 0.617021 (1240 1860);
PAINT ORANGE (1240 1860);
FORCEPROP 2 LASTPIN (1250 1800) $PN 114
J 2
(1240 1810);
DISPLAY 0.617021 (1240 1810);
PAINT ORANGE (1240 1810);
FORCEPROP 2 LASTPIN (1250 1750) $PN 116
J 2
(1240 1760);
DISPLAY 0.617021 (1240 1760);
PAINT ORANGE (1240 1760);
FORCEPROP 2 LASTPIN (1250 1700) $PN 118
J 2
(1240 1710);
DISPLAY 0.617021 (1240 1710);
PAINT ORANGE (1240 1710);
FORCEPROP 2 LASTPIN (1250 1650) $PN 120
J 2
(1240 1660);
DISPLAY 0.617021 (1240 1660);
PAINT ORANGE (1240 1660);
FORCEPROP 2 LASTPIN (1250 1600) $PN 123
J 2
(1240 1610);
DISPLAY 0.617021 (1240 1610);
PAINT ORANGE (1240 1610);
FORCEPROP 2 LASTPIN (1250 1550) $PN 125
J 2
(1240 1560);
DISPLAY 0.617021 (1240 1560);
PAINT ORANGE (1240 1560);
FORCEPROP 2 LASTPIN (1250 1500) $PN 127
J 2
(1240 1510);
DISPLAY 0.617021 (1240 1510);
PAINT ORANGE (1240 1510);
FORCEPROP 2 LASTPIN (1250 1450) $PN 129
J 2
(1240 1460);
DISPLAY 0.617021 (1240 1460);
PAINT ORANGE (1240 1460);
FORCEPROP 2 LASTPIN (1250 1400) $PN 131
J 2
(1240 1410);
DISPLAY 0.617021 (1240 1410);
PAINT ORANGE (1240 1410);
FORCEPROP 2 LASTPIN (1250 1350) $PN 134
J 2
(1240 1360);
DISPLAY 0.617021 (1240 1360);
PAINT ORANGE (1240 1360);
FORCEPROP 2 LASTPIN (1250 1300) $PN 136
J 2
(1240 1310);
DISPLAY 0.617021 (1240 1310);
PAINT ORANGE (1240 1310);
FORCEPROP 2 LASTPIN (1250 1250) $PN 138
J 2
(1240 1260);
DISPLAY 0.617021 (1240 1260);
PAINT ORANGE (1240 1260);
FORCEPROP 2 LASTPIN (2250 3550) $PN 147
J 0
(2260 3560);
DISPLAY 0.617021 (2260 3560);
PAINT ORANGE (2260 3560);
FORCEPROP 2 LASTPIN (2250 3500) $PN 149
J 0
(2260 3510);
DISPLAY 0.617021 (2260 3510);
PAINT ORANGE (2260 3510);
FORCEPROP 2 LASTPIN (2250 3450) $PN 151
J 0
(2260 3460);
DISPLAY 0.617021 (2260 3460);
PAINT ORANGE (2260 3460);
FORCEPROP 2 LASTPIN (2250 3400) $PN 154
J 0
(2260 3410);
DISPLAY 0.617021 (2260 3410);
PAINT ORANGE (2260 3410);
FORCEPROP 2 LASTPIN (2250 3350) $PN 156
J 0
(2260 3360);
DISPLAY 0.617021 (2260 3360);
PAINT ORANGE (2260 3360);
FORCEPROP 2 LASTPIN (2250 3300) $PN 158
J 0
(2260 3310);
DISPLAY 0.617021 (2260 3310);
PAINT ORANGE (2260 3310);
FORCEPROP 2 LASTPIN (2250 3250) $PN 160
J 0
(2260 3260);
DISPLAY 0.617021 (2260 3260);
PAINT ORANGE (2260 3260);
FORCEPROP 2 LASTPIN (2250 3200) $PN 162
J 0
(2260 3210);
DISPLAY 0.617021 (2260 3210);
PAINT ORANGE (2260 3210);
FORCEPROP 2 LASTPIN (2250 3150) $PN 165
J 0
(2260 3160);
DISPLAY 0.617021 (2260 3160);
PAINT ORANGE (2260 3160);
FORCEPROP 2 LASTPIN (2250 3100) $PN 167
J 0
(2260 3110);
DISPLAY 0.617021 (2260 3110);
PAINT ORANGE (2260 3110);
FORCEPROP 2 LASTPIN (2250 3050) $PN 169
J 0
(2260 3060);
DISPLAY 0.617021 (2260 3060);
PAINT ORANGE (2260 3060);
FORCEPROP 2 LASTPIN (2250 3000) $PN 171
J 0
(2260 3010);
DISPLAY 0.617021 (2260 3010);
PAINT ORANGE (2260 3010);
FORCEPROP 2 LASTPIN (2250 2950) $PN 173
J 0
(2260 2960);
DISPLAY 0.617021 (2260 2960);
PAINT ORANGE (2260 2960);
FORCEPROP 2 LASTPIN (2250 2900) $PN 176
J 0
(2260 2910);
DISPLAY 0.617021 (2260 2910);
PAINT ORANGE (2260 2910);
FORCEPROP 2 LASTPIN (2250 2850) $PN 178
J 0
(2260 2860);
DISPLAY 0.617021 (2260 2860);
PAINT ORANGE (2260 2860);
FORCEPROP 2 LASTPIN (2250 2800) $PN 180
J 0
(2260 2810);
DISPLAY 0.617021 (2260 2810);
PAINT ORANGE (2260 2810);
FORCEPROP 2 LASTPIN (2250 2750) $PN 182
J 0
(2260 2760);
DISPLAY 0.617021 (2260 2760);
PAINT ORANGE (2260 2760);
FORCEPROP 2 LASTPIN (2250 2700) $PN 184
J 0
(2260 2710);
DISPLAY 0.617021 (2260 2710);
PAINT ORANGE (2260 2710);
FORCEPROP 2 LASTPIN (2250 2650) $PN 187
J 0
(2260 2660);
DISPLAY 0.617021 (2260 2660);
PAINT ORANGE (2260 2660);
FORCEPROP 2 LASTPIN (2250 2600) $PN 189
J 0
(2260 2610);
DISPLAY 0.617021 (2260 2610);
PAINT ORANGE (2260 2610);
FORCEPROP 2 LASTPIN (2250 2550) $PN 191
J 0
(2260 2560);
DISPLAY 0.617021 (2260 2560);
PAINT ORANGE (2260 2560);
FORCEPROP 2 LASTPIN (2250 2500) $PN 193
J 0
(2260 2510);
DISPLAY 0.617021 (2260 2510);
PAINT ORANGE (2260 2510);
FORCEPROP 2 LASTPIN (2250 2450) $PN 195
J 0
(2260 2460);
DISPLAY 0.617021 (2260 2460);
PAINT ORANGE (2260 2460);
FORCEPROP 2 LASTPIN (2250 2400) $PN 198
J 0
(2260 2410);
DISPLAY 0.617021 (2260 2410);
PAINT ORANGE (2260 2410);
FORCEPROP 2 LASTPIN (2250 2350) $PN 200
J 0
(2260 2360);
DISPLAY 0.617021 (2260 2360);
PAINT ORANGE (2260 2360);
FORCEPROP 2 LASTPIN (2250 2300) $PN 202
J 0
(2260 2310);
DISPLAY 0.617021 (2260 2310);
PAINT ORANGE (2260 2310);
FORCEPROP 2 LASTPIN (2250 2250) $PN 239
J 0
(2260 2260);
DISPLAY 0.617021 (2260 2260);
PAINT ORANGE (2260 2260);
FORCEPROP 2 LASTPIN (2250 2200) $PN 241
J 0
(2260 2210);
DISPLAY 0.617021 (2260 2210);
PAINT ORANGE (2260 2210);
FORCEPROP 2 LASTPIN (2250 2150) $PN 243
J 0
(2260 2160);
DISPLAY 0.617021 (2260 2160);
PAINT ORANGE (2260 2160);
FORCEPROP 2 LASTPIN (2250 2100) $PN 246
J 0
(2260 2110);
DISPLAY 0.617021 (2260 2110);
PAINT ORANGE (2260 2110);
FORCEPROP 2 LASTPIN (2250 2050) $PN 248
J 0
(2260 2060);
DISPLAY 0.617021 (2260 2060);
PAINT ORANGE (2260 2060);
FORCEPROP 2 LASTPIN (2250 2000) $PN 250
J 0
(2260 2010);
DISPLAY 0.617021 (2260 2010);
PAINT ORANGE (2260 2010);
FORCEPROP 2 LASTPIN (2250 1950) $PN 252
J 0
(2260 1960);
DISPLAY 0.617021 (2260 1960);
PAINT ORANGE (2260 1960);
FORCEPROP 2 LASTPIN (2250 1900) $PN 254
J 0
(2260 1910);
DISPLAY 0.617021 (2260 1910);
PAINT ORANGE (2260 1910);
FORCEPROP 2 LASTPIN (2250 1850) $PN 257
J 0
(2260 1860);
DISPLAY 0.617021 (2260 1860);
PAINT ORANGE (2260 1860);
FORCEPROP 2 LASTPIN (2250 1800) $PN 259
J 0
(2260 1810);
DISPLAY 0.617021 (2260 1810);
PAINT ORANGE (2260 1810);
FORCEPROP 2 LASTPIN (2250 1750) $PN 261
J 0
(2260 1760);
DISPLAY 0.617021 (2260 1760);
PAINT ORANGE (2260 1760);
FORCEPROP 2 LASTPIN (2250 1700) $PN 263
J 0
(2260 1710);
DISPLAY 0.617021 (2260 1710);
PAINT ORANGE (2260 1710);
FORCEPROP 2 LASTPIN (2250 1650) $PN 265
J 0
(2260 1660);
DISPLAY 0.617021 (2260 1660);
PAINT ORANGE (2260 1660);
FORCEPROP 2 LASTPIN (2250 1600) $PN 268
J 0
(2260 1610);
DISPLAY 0.617021 (2260 1610);
PAINT ORANGE (2260 1610);
FORCEPROP 2 LASTPIN (2250 1550) $PN 270
J 0
(2260 1560);
DISPLAY 0.617021 (2260 1560);
PAINT ORANGE (2260 1560);
FORCEPROP 2 LASTPIN (2250 1500) $PN 272
J 0
(2260 1510);
DISPLAY 0.617021 (2260 1510);
PAINT ORANGE (2260 1510);
FORCEPROP 2 LASTPIN (2250 1450) $PN 274
J 0
(2260 1460);
DISPLAY 0.617021 (2260 1460);
PAINT ORANGE (2260 1460);
FORCEPROP 2 LASTPIN (2250 1400) $PN 276
J 0
(2260 1410);
DISPLAY 0.617021 (2260 1410);
PAINT ORANGE (2260 1410);
FORCEPROP 2 LASTPIN (2250 1350) $PN 279
J 0
(2260 1360);
DISPLAY 0.617021 (2260 1360);
PAINT ORANGE (2260 1360);
FORCEPROP 2 LASTPIN (2250 1300) $PN 281
J 0
(2260 1310);
DISPLAY 0.617021 (2260 1310);
PAINT ORANGE (2260 1310);
FORCEPROP 2 LASTPIN (2250 1250) $PN 283
J 0
(2260 1260);
DISPLAY 0.617021 (2260 1260);
PAINT ORANGE (2260 1260);
FORCEPROP 1 LAST PACK_TYPE PIP
J 0
(1300 3850);
PAINT SKYBLUE (1300 3850);
DISPLAY INVISIBLE (1300 3850);
FORCEPROP 2 LAST BOM_COST MEM
J 0
(1750 2400);
PAINT ORANGE (1750 2400);
DISPLAY INVISIBLE (1750 2400);
FORCEPROP 2 LAST CDS_LIB mstr_sconn
J 0
(1750 2400);
PAINT ORANGE (1750 2400);
DISPLAY INVISIBLE (1750 2400);
FORCEPROP 2 LAST SEC_TYPE PIP
J 0
(1300 3850);
DISPLAY 1.021277 (1300 3850);
PAINT ORANGE (1300 3850);
DISPLAY INVISIBLE (1300 3850);
FORCEPROP 2 LAST SEC 3
J 0
(1300 3850);
DISPLAY 0.680851 (1300 3850);
PAINT MONO (1300 3850);
DISPLAY INVISIBLE (1300 3850);
FORCEPROP 2 LAST CDS_LOCATION J4A1
J 0
(1300 3800);
DISPLAY 0.617021 (1300 3800);
PAINT AQUA (1300 3800);
DISPLAY INVISIBLE (1300 3800);
FORCEPROP 1 LAST PATH I43
J 0
(1750 3750);
PAINT GREEN (1750 3750);
DISPLAY INVISIBLE (1750 3750);
FORCEPROP 2 LAST ROOM DDR4_CH_F
J 0
(1750 2400);
PAINT ORANGE (1750 2400);
DISPLAY INVISIBLE (1750 2400);
FORCEADD GND..1
R 2
(1050 1075);
FORCEPROP 3 LASTPIN (1050 1125) SIG_NAME GND\g
J 0
(1060 1135);
DISPLAY 0.659574 (1060 1135);
PAINT MONO (1060 1135);
DISPLAY INVISIBLE (1060 1135);
FORCEPROP 1 LAST VOLTAGE 0
J 0
(1050 1075);
PAINT SKYBLUE (1050 1075);
DISPLAY INVISIBLE (1050 1075);
FORCEPROP 2 LAST BOM_COST MEM
J 0
(1050 1080);
PAINT ORANGE (1050 1080);
DISPLAY INVISIBLE (1050 1080);
FORCEPROP 1 LAST SIZE 1B
J 2
(975 1025);
DISPLAY 1.170213 (975 1025);
PAINT GREEN (975 1025);
DISPLAY INVISIBLE (975 1025);
FORCEPROP 2 LAST CDS_LIB mstr_symbols
J 0
(1050 1075);
DISPLAY 0.787234 (1050 1075);
PAINT MONO (1050 1075);
DISPLAY INVISIBLE (1050 1075);
FORCEPROP 1 LAST BODY_TYPE PLUMBING
J 2
(1095 1032);
DISPLAY 0.340426 (1095 1032);
PAINT GREEN (1095 1032);
DISPLAY INVISIBLE (1095 1032);
FORCEPROP 1 LAST PATH I44
J 2
(975 1075);
DISPLAY 0.936170 (975 1075);
PAINT GREEN (975 1075);
DISPLAY INVISIBLE (975 1075);
FORCEPROP 2 LAST ROOM DDR4_CH_C
J 0
(1050 1080);
PAINT ORANGE (1050 1080);
DISPLAY INVISIBLE (1050 1080);
FORCEPROP 1 LAST HDL_POWER GND
J 2
(1050 1225);
DISPLAY 0.553191 (1050 1225);
PAINT GREEN (1050 1225);
DISPLAY INVISIBLE (1050 1225);
FORCEADD OFFPAGE..3
(-1000 4525);
FORCEPROP 2 LAST $XR1 54 
J 0
(-696 4525);
DISPLAY 0.638298 (-696 4525);
PAINT MONO (-696 4525);
FORCEPROP 2 LAST $XR0 28 
J 0
(-786 4525);
DISPLAY 0.638298 (-786 4525);
PAINT MONO (-786 4525);
FORCEPROP 2 LAST CDS_LIB mstr_standard
J 0
(-1000 4525);
DISPLAY 0.787234 (-1000 4525);
PAINT MONO (-1000 4525);
DISPLAY INVISIBLE (-1000 4525);
FORCEPROP 1 LAST OFFPAGE TRUE
J 0
(-675 4400);
DISPLAY 0.936170 (-675 4400);
PAINT GREEN (-675 4400);
DISPLAY INVISIBLE (-675 4400);
FORCEPROP 1 LAST COMMENT_BODY TRUE
J 0
(-1050 4425);
DISPLAY 0.936170 (-1050 4425);
PAINT GREEN (-1050 4425);
DISPLAY INVISIBLE (-1050 4425);
FORCEPROP 2 LAST PATH I45
J 0
(-800 4600);
DISPLAY 0.787234 (-800 4600);
PAINT MONO (-800 4600);
DISPLAY INVISIBLE (-800 4600);
FORCEADD TAP..6
R 2
(-1550 4475);
FORCEPROP 3 LASTPIN (-1600 4475) SIG_NAME M_F_DQ<62>
J 0
(-1590 4485);
DISPLAY 0.659574 (-1590 4485);
PAINT MONO (-1590 4485);
DISPLAY INVISIBLE (-1590 4485);
FORCEPROP 1 LASTPIN (-1600 4475) BN 62
J 2
(-1550 4485);
DISPLAY 0.617021 (-1550 4485);
PAINT PINK (-1550 4485);
FORCEPROP 2 LAST CDS_LIB mstr_standard
J 2
(-1550 4475);
DISPLAY 0.787234 (-1550 4475);
PAINT MONO (-1550 4475);
DISPLAY INVISIBLE (-1550 4475);
FORCEPROP 1 LAST BODY_TYPE PLUMBING
J 2
(-1550 4425);
DISPLAY 1.234043 (-1550 4425);
PAINT GREEN (-1550 4425);
DISPLAY INVISIBLE (-1550 4425);
FORCEPROP 1 LAST HDL_TAP TRUE
J 2
(-1875 4350);
DISPLAY 1.234043 (-1875 4350);
PAINT GREEN (-1875 4350);
DISPLAY INVISIBLE (-1875 4350);
FORCEPROP 1 LAST PATH I46
J 2
(-1550 4475);
DISPLAY 0.936170 (-1550 4475);
PAINT GREEN (-1550 4475);
DISPLAY INVISIBLE (-1550 4475);
FORCEADD TAP..6
R 2
(-1550 4425);
FORCEPROP 3 LASTPIN (-1600 4425) SIG_NAME M_F_DQ<63>
J 0
(-1590 4435);
DISPLAY 0.659574 (-1590 4435);
PAINT MONO (-1590 4435);
DISPLAY INVISIBLE (-1590 4435);
FORCEPROP 1 LASTPIN (-1600 4425) BN 63
J 2
(-1550 4435);
DISPLAY 0.617021 (-1550 4435);
PAINT PINK (-1550 4435);
FORCEPROP 2 LAST CDS_LIB mstr_standard
J 2
(-1550 4425);
DISPLAY 0.787234 (-1550 4425);
PAINT MONO (-1550 4425);
DISPLAY INVISIBLE (-1550 4425);
FORCEPROP 1 LAST BODY_TYPE PLUMBING
J 2
(-1550 4375);
DISPLAY 1.234043 (-1550 4375);
PAINT GREEN (-1550 4375);
DISPLAY INVISIBLE (-1550 4375);
FORCEPROP 1 LAST HDL_TAP TRUE
J 2
(-1875 4300);
DISPLAY 1.234043 (-1875 4300);
PAINT GREEN (-1875 4300);
DISPLAY INVISIBLE (-1875 4300);
FORCEPROP 1 LAST PATH I47
J 2
(-1550 4425);
DISPLAY 0.936170 (-1550 4425);
PAINT GREEN (-1550 4425);
DISPLAY INVISIBLE (-1550 4425);
FORCEADD TAP..6
R 2
(-1550 4325);
FORCEPROP 3 LASTPIN (-1600 4325) SIG_NAME M_F_DQ<61>
J 0
(-1590 4335);
DISPLAY 0.659574 (-1590 4335);
PAINT MONO (-1590 4335);
DISPLAY INVISIBLE (-1590 4335);
FORCEPROP 1 LASTPIN (-1600 4325) BN 61
J 2
(-1550 4335);
DISPLAY 0.617021 (-1550 4335);
PAINT PINK (-1550 4335);
FORCEPROP 2 LAST CDS_LIB mstr_standard
J 2
(-1550 4325);
DISPLAY 0.787234 (-1550 4325);
PAINT MONO (-1550 4325);
DISPLAY INVISIBLE (-1550 4325);
FORCEPROP 1 LAST BODY_TYPE PLUMBING
J 2
(-1550 4275);
DISPLAY 1.234043 (-1550 4275);
PAINT GREEN (-1550 4275);
DISPLAY INVISIBLE (-1550 4275);
FORCEPROP 1 LAST HDL_TAP TRUE
J 2
(-1875 4200);
DISPLAY 1.234043 (-1875 4200);
PAINT GREEN (-1875 4200);
DISPLAY INVISIBLE (-1875 4200);
FORCEPROP 1 LAST PATH I48
J 2
(-1550 4325);
DISPLAY 0.936170 (-1550 4325);
PAINT GREEN (-1550 4325);
DISPLAY INVISIBLE (-1550 4325);
FORCEADD TAP..6
R 2
(-1550 4375);
FORCEPROP 3 LASTPIN (-1600 4375) SIG_NAME M_F_DQ<60>
J 0
(-1590 4385);
DISPLAY 0.659574 (-1590 4385);
PAINT MONO (-1590 4385);
DISPLAY INVISIBLE (-1590 4385);
FORCEPROP 1 LASTPIN (-1600 4375) BN 60
J 2
(-1550 4385);
DISPLAY 0.617021 (-1550 4385);
PAINT PINK (-1550 4385);
FORCEPROP 2 LAST CDS_LIB mstr_standard
J 2
(-1550 4375);
DISPLAY 0.787234 (-1550 4375);
PAINT MONO (-1550 4375);
DISPLAY INVISIBLE (-1550 4375);
FORCEPROP 1 LAST BODY_TYPE PLUMBING
J 2
(-1550 4325);
DISPLAY 1.234043 (-1550 4325);
PAINT GREEN (-1550 4325);
DISPLAY INVISIBLE (-1550 4325);
FORCEPROP 1 LAST HDL_TAP TRUE
J 2
(-1875 4250);
DISPLAY 1.234043 (-1875 4250);
PAINT GREEN (-1875 4250);
DISPLAY INVISIBLE (-1875 4250);
FORCEPROP 1 LAST PATH I49
J 2
(-1550 4375);
DISPLAY 0.936170 (-1550 4375);
PAINT GREEN (-1550 4375);
DISPLAY INVISIBLE (-1550 4375);
FORCEADD TAP..6
R 2
(850 5050);
FORCEPROP 3 LASTPIN (800 5050) SIG_NAME M_F_DQS_DN<16>
J 0
(810 5060);
DISPLAY 0.659574 (810 5060);
PAINT MONO (810 5060);
DISPLAY INVISIBLE (810 5060);
FORCEPROP 1 LASTPIN (800 5050) BN 16
J 2
(850 5060);
DISPLAY 0.617021 (850 5060);
PAINT PINK (850 5060);
FORCEPROP 2 LAST CDS_LIB mstr_standard
J 0
(850 5050);
DISPLAY 0.787234 (850 5050);
PAINT MONO (850 5050);
DISPLAY INVISIBLE (850 5050);
FORCEPROP 1 LAST BODY_TYPE PLUMBING
J 2
(850 5000);
DISPLAY 1.234043 (850 5000);
PAINT GREEN (850 5000);
DISPLAY INVISIBLE (850 5000);
FORCEPROP 1 LAST HDL_TAP TRUE
J 2
(525 4925);
DISPLAY 1.234043 (525 4925);
PAINT GREEN (525 4925);
DISPLAY INVISIBLE (525 4925);
FORCEPROP 1 LAST PATH I5
J 2
(850 5050);
DISPLAY 0.936170 (850 5050);
PAINT GREEN (850 5050);
DISPLAY INVISIBLE (850 5050);
FORCEADD TAP..6
R 2
(-1550 4275);
FORCEPROP 3 LASTPIN (-1600 4275) SIG_NAME M_F_DQ<58>
J 0
(-1590 4285);
DISPLAY 0.659574 (-1590 4285);
PAINT MONO (-1590 4285);
DISPLAY INVISIBLE (-1590 4285);
FORCEPROP 1 LASTPIN (-1600 4275) BN 58
J 2
(-1550 4285);
DISPLAY 0.617021 (-1550 4285);
PAINT PINK (-1550 4285);
FORCEPROP 2 LAST CDS_LIB mstr_standard
J 2
(-1550 4275);
DISPLAY 0.787234 (-1550 4275);
PAINT MONO (-1550 4275);
DISPLAY INVISIBLE (-1550 4275);
FORCEPROP 1 LAST BODY_TYPE PLUMBING
J 2
(-1550 4225);
DISPLAY 1.234043 (-1550 4225);
PAINT GREEN (-1550 4225);
DISPLAY INVISIBLE (-1550 4225);
FORCEPROP 1 LAST HDL_TAP TRUE
J 2
(-1875 4150);
DISPLAY 1.234043 (-1875 4150);
PAINT GREEN (-1875 4150);
DISPLAY INVISIBLE (-1875 4150);
FORCEPROP 1 LAST PATH I50
J 2
(-1550 4275);
DISPLAY 0.936170 (-1550 4275);
PAINT GREEN (-1550 4275);
DISPLAY INVISIBLE (-1550 4275);
FORCEADD TAP..6
R 2
(-1550 4175);
FORCEPROP 3 LASTPIN (-1600 4175) SIG_NAME M_F_DQ<56>
J 0
(-1590 4185);
DISPLAY 0.659574 (-1590 4185);
PAINT MONO (-1590 4185);
DISPLAY INVISIBLE (-1590 4185);
FORCEPROP 1 LASTPIN (-1600 4175) BN 56
J 2
(-1550 4185);
DISPLAY 0.617021 (-1550 4185);
PAINT PINK (-1550 4185);
FORCEPROP 2 LAST CDS_LIB mstr_standard
J 2
(-1550 4175);
DISPLAY 0.787234 (-1550 4175);
PAINT MONO (-1550 4175);
DISPLAY INVISIBLE (-1550 4175);
FORCEPROP 1 LAST BODY_TYPE PLUMBING
J 2
(-1550 4125);
DISPLAY 1.234043 (-1550 4125);
PAINT GREEN (-1550 4125);
DISPLAY INVISIBLE (-1550 4125);
FORCEPROP 1 LAST HDL_TAP TRUE
J 2
(-1875 4050);
DISPLAY 1.234043 (-1875 4050);
PAINT GREEN (-1875 4050);
DISPLAY INVISIBLE (-1875 4050);
FORCEPROP 1 LAST PATH I51
J 2
(-1550 4175);
DISPLAY 0.936170 (-1550 4175);
PAINT GREEN (-1550 4175);
DISPLAY INVISIBLE (-1550 4175);
FORCEADD TAP..6
R 2
(-1550 4225);
FORCEPROP 3 LASTPIN (-1600 4225) SIG_NAME M_F_DQ<59>
J 0
(-1590 4235);
DISPLAY 0.659574 (-1590 4235);
PAINT MONO (-1590 4235);
DISPLAY INVISIBLE (-1590 4235);
FORCEPROP 1 LASTPIN (-1600 4225) BN 59
J 2
(-1550 4235);
DISPLAY 0.617021 (-1550 4235);
PAINT PINK (-1550 4235);
FORCEPROP 2 LAST CDS_LIB mstr_standard
J 2
(-1550 4225);
DISPLAY 0.787234 (-1550 4225);
PAINT MONO (-1550 4225);
DISPLAY INVISIBLE (-1550 4225);
FORCEPROP 1 LAST BODY_TYPE PLUMBING
J 2
(-1550 4175);
DISPLAY 1.234043 (-1550 4175);
PAINT GREEN (-1550 4175);
DISPLAY INVISIBLE (-1550 4175);
FORCEPROP 1 LAST HDL_TAP TRUE
J 2
(-1875 4100);
DISPLAY 1.234043 (-1875 4100);
PAINT GREEN (-1875 4100);
DISPLAY INVISIBLE (-1875 4100);
FORCEPROP 1 LAST PATH I52
J 2
(-1550 4225);
DISPLAY 0.936170 (-1550 4225);
PAINT GREEN (-1550 4225);
DISPLAY INVISIBLE (-1550 4225);
FORCEADD TAP..6
R 2
(-1550 4125);
FORCEPROP 3 LASTPIN (-1600 4125) SIG_NAME M_F_DQ<57>
J 0
(-1590 4135);
DISPLAY 0.659574 (-1590 4135);
PAINT MONO (-1590 4135);
DISPLAY INVISIBLE (-1590 4135);
FORCEPROP 1 LASTPIN (-1600 4125) BN 57
J 2
(-1550 4135);
DISPLAY 0.617021 (-1550 4135);
PAINT PINK (-1550 4135);
FORCEPROP 2 LAST CDS_LIB mstr_standard
J 2
(-1550 4125);
DISPLAY 0.787234 (-1550 4125);
PAINT MONO (-1550 4125);
DISPLAY INVISIBLE (-1550 4125);
FORCEPROP 1 LAST BODY_TYPE PLUMBING
J 2
(-1550 4075);
DISPLAY 1.234043 (-1550 4075);
PAINT GREEN (-1550 4075);
DISPLAY INVISIBLE (-1550 4075);
FORCEPROP 1 LAST HDL_TAP TRUE
J 2
(-1875 4000);
DISPLAY 1.234043 (-1875 4000);
PAINT GREEN (-1875 4000);
DISPLAY INVISIBLE (-1875 4000);
FORCEPROP 1 LAST PATH I53
J 2
(-1550 4125);
DISPLAY 0.936170 (-1550 4125);
PAINT GREEN (-1550 4125);
DISPLAY INVISIBLE (-1550 4125);
FORCEADD TAP..6
R 2
(-1550 4075);
FORCEPROP 3 LASTPIN (-1600 4075) SIG_NAME M_F_DQ<54>
J 0
(-1590 4085);
DISPLAY 0.659574 (-1590 4085);
PAINT MONO (-1590 4085);
DISPLAY INVISIBLE (-1590 4085);
FORCEPROP 1 LASTPIN (-1600 4075) BN 54
J 2
(-1550 4085);
DISPLAY 0.617021 (-1550 4085);
PAINT PINK (-1550 4085);
FORCEPROP 2 LAST CDS_LIB mstr_standard
J 2
(-1550 4075);
DISPLAY 0.787234 (-1550 4075);
PAINT MONO (-1550 4075);
DISPLAY INVISIBLE (-1550 4075);
FORCEPROP 1 LAST BODY_TYPE PLUMBING
J 2
(-1550 4025);
DISPLAY 1.234043 (-1550 4025);
PAINT GREEN (-1550 4025);
DISPLAY INVISIBLE (-1550 4025);
FORCEPROP 1 LAST HDL_TAP TRUE
J 2
(-1875 3950);
DISPLAY 1.234043 (-1875 3950);
PAINT GREEN (-1875 3950);
DISPLAY INVISIBLE (-1875 3950);
FORCEPROP 1 LAST PATH I54
J 2
(-1550 4075);
DISPLAY 0.936170 (-1550 4075);
PAINT GREEN (-1550 4075);
DISPLAY INVISIBLE (-1550 4075);
FORCEADD TAP..6
R 2
(-1550 3975);
FORCEPROP 3 LASTPIN (-1600 3975) SIG_NAME M_F_DQ<52>
J 0
(-1590 3985);
DISPLAY 0.659574 (-1590 3985);
PAINT MONO (-1590 3985);
DISPLAY INVISIBLE (-1590 3985);
FORCEPROP 1 LASTPIN (-1600 3975) BN 52
J 2
(-1550 3985);
DISPLAY 0.617021 (-1550 3985);
PAINT PINK (-1550 3985);
FORCEPROP 2 LAST CDS_LIB mstr_standard
J 2
(-1550 3975);
DISPLAY 0.787234 (-1550 3975);
PAINT MONO (-1550 3975);
DISPLAY INVISIBLE (-1550 3975);
FORCEPROP 1 LAST BODY_TYPE PLUMBING
J 2
(-1550 3925);
DISPLAY 1.234043 (-1550 3925);
PAINT GREEN (-1550 3925);
DISPLAY INVISIBLE (-1550 3925);
FORCEPROP 1 LAST HDL_TAP TRUE
J 2
(-1875 3850);
DISPLAY 1.234043 (-1875 3850);
PAINT GREEN (-1875 3850);
DISPLAY INVISIBLE (-1875 3850);
FORCEPROP 1 LAST PATH I55
J 2
(-1550 3975);
DISPLAY 0.936170 (-1550 3975);
PAINT GREEN (-1550 3975);
DISPLAY INVISIBLE (-1550 3975);
FORCEADD TAP..6
R 2
(-1550 4025);
FORCEPROP 3 LASTPIN (-1600 4025) SIG_NAME M_F_DQ<55>
J 0
(-1590 4035);
DISPLAY 0.659574 (-1590 4035);
PAINT MONO (-1590 4035);
DISPLAY INVISIBLE (-1590 4035);
FORCEPROP 1 LASTPIN (-1600 4025) BN 55
J 2
(-1550 4035);
DISPLAY 0.617021 (-1550 4035);
PAINT PINK (-1550 4035);
FORCEPROP 2 LAST CDS_LIB mstr_standard
J 2
(-1550 4025);
DISPLAY 0.787234 (-1550 4025);
PAINT MONO (-1550 4025);
DISPLAY INVISIBLE (-1550 4025);
FORCEPROP 1 LAST BODY_TYPE PLUMBING
J 2
(-1550 3975);
DISPLAY 1.234043 (-1550 3975);
PAINT GREEN (-1550 3975);
DISPLAY INVISIBLE (-1550 3975);
FORCEPROP 1 LAST HDL_TAP TRUE
J 2
(-1875 3900);
DISPLAY 1.234043 (-1875 3900);
PAINT GREEN (-1875 3900);
DISPLAY INVISIBLE (-1875 3900);
FORCEPROP 1 LAST PATH I56
J 2
(-1550 4025);
DISPLAY 0.936170 (-1550 4025);
PAINT GREEN (-1550 4025);
DISPLAY INVISIBLE (-1550 4025);
FORCEADD TAP..6
R 2
(-1550 3925);
FORCEPROP 3 LASTPIN (-1600 3925) SIG_NAME M_F_DQ<53>
J 0
(-1590 3935);
DISPLAY 0.659574 (-1590 3935);
PAINT MONO (-1590 3935);
DISPLAY INVISIBLE (-1590 3935);
FORCEPROP 1 LASTPIN (-1600 3925) BN 53
J 2
(-1550 3935);
DISPLAY 0.617021 (-1550 3935);
PAINT PINK (-1550 3935);
FORCEPROP 2 LAST CDS_LIB mstr_standard
J 2
(-1550 3925);
DISPLAY 0.787234 (-1550 3925);
PAINT MONO (-1550 3925);
DISPLAY INVISIBLE (-1550 3925);
FORCEPROP 1 LAST BODY_TYPE PLUMBING
J 2
(-1550 3875);
DISPLAY 1.234043 (-1550 3875);
PAINT GREEN (-1550 3875);
DISPLAY INVISIBLE (-1550 3875);
FORCEPROP 1 LAST HDL_TAP TRUE
J 2
(-1875 3800);
DISPLAY 1.234043 (-1875 3800);
PAINT GREEN (-1875 3800);
DISPLAY INVISIBLE (-1875 3800);
FORCEPROP 1 LAST PATH I57
J 2
(-1550 3925);
DISPLAY 0.936170 (-1550 3925);
PAINT GREEN (-1550 3925);
DISPLAY INVISIBLE (-1550 3925);
FORCEADD TAP..6
R 2
(-1550 3875);
FORCEPROP 3 LASTPIN (-1600 3875) SIG_NAME M_F_DQ<50>
J 0
(-1590 3885);
DISPLAY 0.659574 (-1590 3885);
PAINT MONO (-1590 3885);
DISPLAY INVISIBLE (-1590 3885);
FORCEPROP 1 LASTPIN (-1600 3875) BN 50
J 2
(-1550 3885);
DISPLAY 0.617021 (-1550 3885);
PAINT PINK (-1550 3885);
FORCEPROP 2 LAST CDS_LIB mstr_standard
J 2
(-1550 3875);
DISPLAY 0.787234 (-1550 3875);
PAINT MONO (-1550 3875);
DISPLAY INVISIBLE (-1550 3875);
FORCEPROP 1 LAST BODY_TYPE PLUMBING
J 2
(-1550 3825);
DISPLAY 1.234043 (-1550 3825);
PAINT GREEN (-1550 3825);
DISPLAY INVISIBLE (-1550 3825);
FORCEPROP 1 LAST HDL_TAP TRUE
J 2
(-1875 3750);
DISPLAY 1.234043 (-1875 3750);
PAINT GREEN (-1875 3750);
DISPLAY INVISIBLE (-1875 3750);
FORCEPROP 1 LAST PATH I58
J 2
(-1550 3875);
DISPLAY 0.936170 (-1550 3875);
PAINT GREEN (-1550 3875);
DISPLAY INVISIBLE (-1550 3875);
FORCEADD TAP..6
R 2
(-1550 3825);
FORCEPROP 3 LASTPIN (-1600 3825) SIG_NAME M_F_DQ<51>
J 0
(-1590 3835);
DISPLAY 0.659574 (-1590 3835);
PAINT MONO (-1590 3835);
DISPLAY INVISIBLE (-1590 3835);
FORCEPROP 1 LASTPIN (-1600 3825) BN 51
J 2
(-1550 3835);
DISPLAY 0.617021 (-1550 3835);
PAINT PINK (-1550 3835);
FORCEPROP 2 LAST CDS_LIB mstr_standard
J 2
(-1550 3825);
DISPLAY 0.787234 (-1550 3825);
PAINT MONO (-1550 3825);
DISPLAY INVISIBLE (-1550 3825);
FORCEPROP 1 LAST BODY_TYPE PLUMBING
J 2
(-1550 3775);
DISPLAY 1.234043 (-1550 3775);
PAINT GREEN (-1550 3775);
DISPLAY INVISIBLE (-1550 3775);
FORCEPROP 1 LAST HDL_TAP TRUE
J 2
(-1875 3700);
DISPLAY 1.234043 (-1875 3700);
PAINT GREEN (-1875 3700);
DISPLAY INVISIBLE (-1875 3700);
FORCEPROP 1 LAST PATH I59
J 2
(-1550 3825);
DISPLAY 0.936170 (-1550 3825);
PAINT GREEN (-1550 3825);
DISPLAY INVISIBLE (-1550 3825);
FORCEADD TAP..6
R 2
(850 4950);
FORCEPROP 3 LASTPIN (800 4950) SIG_NAME M_F_DQS_DN<15>
J 0
(810 4960);
DISPLAY 0.659574 (810 4960);
PAINT MONO (810 4960);
DISPLAY INVISIBLE (810 4960);
FORCEPROP 1 LASTPIN (800 4950) BN 15
J 2
(850 4960);
DISPLAY 0.617021 (850 4960);
PAINT PINK (850 4960);
FORCEPROP 2 LAST CDS_LIB mstr_standard
J 0
(850 4950);
DISPLAY 0.787234 (850 4950);
PAINT MONO (850 4950);
DISPLAY INVISIBLE (850 4950);
FORCEPROP 1 LAST BODY_TYPE PLUMBING
J 2
(850 4900);
DISPLAY 1.234043 (850 4900);
PAINT GREEN (850 4900);
DISPLAY INVISIBLE (850 4900);
FORCEPROP 1 LAST HDL_TAP TRUE
J 2
(525 4825);
DISPLAY 1.234043 (525 4825);
PAINT GREEN (525 4825);
DISPLAY INVISIBLE (525 4825);
FORCEPROP 1 LAST PATH I6
J 2
(850 4950);
DISPLAY 0.936170 (850 4950);
PAINT GREEN (850 4950);
DISPLAY INVISIBLE (850 4950);
FORCEADD TAP..6
R 2
(-1550 3775);
FORCEPROP 3 LASTPIN (-1600 3775) SIG_NAME M_F_DQ<48>
J 0
(-1590 3785);
DISPLAY 0.659574 (-1590 3785);
PAINT MONO (-1590 3785);
DISPLAY INVISIBLE (-1590 3785);
FORCEPROP 1 LASTPIN (-1600 3775) BN 48
J 2
(-1550 3785);
DISPLAY 0.617021 (-1550 3785);
PAINT PINK (-1550 3785);
FORCEPROP 2 LAST CDS_LIB mstr_standard
J 2
(-1550 3775);
DISPLAY 0.787234 (-1550 3775);
PAINT MONO (-1550 3775);
DISPLAY INVISIBLE (-1550 3775);
FORCEPROP 1 LAST BODY_TYPE PLUMBING
J 2
(-1550 3725);
DISPLAY 1.234043 (-1550 3725);
PAINT GREEN (-1550 3725);
DISPLAY INVISIBLE (-1550 3725);
FORCEPROP 1 LAST HDL_TAP TRUE
J 2
(-1875 3650);
DISPLAY 1.234043 (-1875 3650);
PAINT GREEN (-1875 3650);
DISPLAY INVISIBLE (-1875 3650);
FORCEPROP 1 LAST PATH I60
J 2
(-1550 3775);
DISPLAY 0.936170 (-1550 3775);
PAINT GREEN (-1550 3775);
DISPLAY INVISIBLE (-1550 3775);
FORCEADD TAP..6
R 2
(-1550 3675);
FORCEPROP 3 LASTPIN (-1600 3675) SIG_NAME M_F_DQ<46>
J 0
(-1590 3685);
DISPLAY 0.659574 (-1590 3685);
PAINT MONO (-1590 3685);
DISPLAY INVISIBLE (-1590 3685);
FORCEPROP 1 LASTPIN (-1600 3675) BN 46
J 2
(-1550 3685);
DISPLAY 0.617021 (-1550 3685);
PAINT PINK (-1550 3685);
FORCEPROP 2 LAST CDS_LIB mstr_standard
J 2
(-1550 3675);
DISPLAY 0.787234 (-1550 3675);
PAINT MONO (-1550 3675);
DISPLAY INVISIBLE (-1550 3675);
FORCEPROP 1 LAST BODY_TYPE PLUMBING
J 2
(-1550 3625);
DISPLAY 1.234043 (-1550 3625);
PAINT GREEN (-1550 3625);
DISPLAY INVISIBLE (-1550 3625);
FORCEPROP 1 LAST HDL_TAP TRUE
J 2
(-1875 3550);
DISPLAY 1.234043 (-1875 3550);
PAINT GREEN (-1875 3550);
DISPLAY INVISIBLE (-1875 3550);
FORCEPROP 1 LAST PATH I61
J 2
(-1550 3675);
DISPLAY 0.936170 (-1550 3675);
PAINT GREEN (-1550 3675);
DISPLAY INVISIBLE (-1550 3675);
FORCEADD TAP..6
R 2
(-1550 3725);
FORCEPROP 3 LASTPIN (-1600 3725) SIG_NAME M_F_DQ<49>
J 0
(-1590 3735);
DISPLAY 0.659574 (-1590 3735);
PAINT MONO (-1590 3735);
DISPLAY INVISIBLE (-1590 3735);
FORCEPROP 1 LASTPIN (-1600 3725) BN 49
J 2
(-1550 3735);
DISPLAY 0.617021 (-1550 3735);
PAINT PINK (-1550 3735);
FORCEPROP 2 LAST CDS_LIB mstr_standard
J 2
(-1550 3725);
DISPLAY 0.787234 (-1550 3725);
PAINT MONO (-1550 3725);
DISPLAY INVISIBLE (-1550 3725);
FORCEPROP 1 LAST BODY_TYPE PLUMBING
J 2
(-1550 3675);
DISPLAY 1.234043 (-1550 3675);
PAINT GREEN (-1550 3675);
DISPLAY INVISIBLE (-1550 3675);
FORCEPROP 1 LAST HDL_TAP TRUE
J 2
(-1875 3600);
DISPLAY 1.234043 (-1875 3600);
PAINT GREEN (-1875 3600);
DISPLAY INVISIBLE (-1875 3600);
FORCEPROP 1 LAST PATH I62
J 2
(-1550 3725);
DISPLAY 0.936170 (-1550 3725);
PAINT GREEN (-1550 3725);
DISPLAY INVISIBLE (-1550 3725);
FORCEADD TAP..6
R 2
(-1550 3625);
FORCEPROP 3 LASTPIN (-1600 3625) SIG_NAME M_F_DQ<47>
J 0
(-1590 3635);
DISPLAY 0.659574 (-1590 3635);
PAINT MONO (-1590 3635);
DISPLAY INVISIBLE (-1590 3635);
FORCEPROP 1 LASTPIN (-1600 3625) BN 47
J 2
(-1550 3635);
DISPLAY 0.617021 (-1550 3635);
PAINT PINK (-1550 3635);
FORCEPROP 2 LAST CDS_LIB mstr_standard
J 2
(-1550 3625);
DISPLAY 0.787234 (-1550 3625);
PAINT MONO (-1550 3625);
DISPLAY INVISIBLE (-1550 3625);
FORCEPROP 1 LAST BODY_TYPE PLUMBING
J 2
(-1550 3575);
DISPLAY 1.234043 (-1550 3575);
PAINT GREEN (-1550 3575);
DISPLAY INVISIBLE (-1550 3575);
FORCEPROP 1 LAST HDL_TAP TRUE
J 2
(-1875 3500);
DISPLAY 1.234043 (-1875 3500);
PAINT GREEN (-1875 3500);
DISPLAY INVISIBLE (-1875 3500);
FORCEPROP 1 LAST PATH I63
J 2
(-1550 3625);
DISPLAY 0.936170 (-1550 3625);
PAINT GREEN (-1550 3625);
DISPLAY INVISIBLE (-1550 3625);
FORCEADD TAP..6
R 2
(-1550 3575);
FORCEPROP 3 LASTPIN (-1600 3575) SIG_NAME M_F_DQ<44>
J 0
(-1590 3585);
DISPLAY 0.659574 (-1590 3585);
PAINT MONO (-1590 3585);
DISPLAY INVISIBLE (-1590 3585);
FORCEPROP 1 LASTPIN (-1600 3575) BN 44
J 2
(-1550 3585);
DISPLAY 0.617021 (-1550 3585);
PAINT PINK (-1550 3585);
FORCEPROP 2 LAST CDS_LIB mstr_standard
J 2
(-1550 3575);
DISPLAY 0.787234 (-1550 3575);
PAINT MONO (-1550 3575);
DISPLAY INVISIBLE (-1550 3575);
FORCEPROP 1 LAST BODY_TYPE PLUMBING
J 2
(-1550 3525);
DISPLAY 1.234043 (-1550 3525);
PAINT GREEN (-1550 3525);
DISPLAY INVISIBLE (-1550 3525);
FORCEPROP 1 LAST HDL_TAP TRUE
J 2
(-1875 3450);
DISPLAY 1.234043 (-1875 3450);
PAINT GREEN (-1875 3450);
DISPLAY INVISIBLE (-1875 3450);
FORCEPROP 1 LAST PATH I64
J 2
(-1550 3575);
DISPLAY 0.936170 (-1550 3575);
PAINT GREEN (-1550 3575);
DISPLAY INVISIBLE (-1550 3575);
FORCEADD TAP..6
R 2
(-1550 3525);
FORCEPROP 3 LASTPIN (-1600 3525) SIG_NAME M_F_DQ<45>
J 0
(-1590 3535);
DISPLAY 0.659574 (-1590 3535);
PAINT MONO (-1590 3535);
DISPLAY INVISIBLE (-1590 3535);
FORCEPROP 1 LASTPIN (-1600 3525) BN 45
J 2
(-1550 3535);
DISPLAY 0.617021 (-1550 3535);
PAINT PINK (-1550 3535);
FORCEPROP 2 LAST CDS_LIB mstr_standard
J 2
(-1550 3525);
DISPLAY 0.787234 (-1550 3525);
PAINT MONO (-1550 3525);
DISPLAY INVISIBLE (-1550 3525);
FORCEPROP 1 LAST BODY_TYPE PLUMBING
J 2
(-1550 3475);
DISPLAY 1.234043 (-1550 3475);
PAINT GREEN (-1550 3475);
DISPLAY INVISIBLE (-1550 3475);
FORCEPROP 1 LAST HDL_TAP TRUE
J 2
(-1875 3400);
DISPLAY 1.234043 (-1875 3400);
PAINT GREEN (-1875 3400);
DISPLAY INVISIBLE (-1875 3400);
FORCEPROP 1 LAST PATH I65
J 2
(-1550 3525);
DISPLAY 0.936170 (-1550 3525);
PAINT GREEN (-1550 3525);
DISPLAY INVISIBLE (-1550 3525);
FORCEADD SCONN288_H44441004..2
(-50 4350);
FORCEPROP 1 LAST LOCATION J4A1
J 0
(-450 5450);
DISPLAY 0.617021 (-450 5450);
PAINT AQUA (-450 5450);
FORCEPROP 1 LAST MATERIAL SCONN
J 0
(-450 5400);
DISPLAY 0.617021 (-450 5400);
PAINT SKYBLUE (-450 5400);
FORCEPROP 2 LASTPIN (400 5200) $PN 51
J 0
(410 5210);
DISPLAY 0.617021 (410 5210);
PAINT ORANGE (410 5210);
FORCEPROP 2 LASTPIN (400 5150) $PN 52
J 0
(410 5160);
DISPLAY 0.617021 (410 5160);
PAINT ORANGE (410 5160);
FORCEPROP 2 LASTPIN (400 5100) $PN 132
J 0
(410 5110);
DISPLAY 0.617021 (410 5110);
PAINT ORANGE (410 5110);
FORCEPROP 2 LASTPIN (400 5050) $PN 133
J 0
(410 5060);
DISPLAY 0.617021 (410 5060);
PAINT ORANGE (410 5060);
FORCEPROP 2 LASTPIN (400 5000) $PN 121
J 0
(410 5010);
DISPLAY 0.617021 (410 5010);
PAINT ORANGE (410 5010);
FORCEPROP 2 LASTPIN (400 4950) $PN 122
J 0
(410 4960);
DISPLAY 0.617021 (410 4960);
PAINT ORANGE (410 4960);
FORCEPROP 2 LASTPIN (400 4900) $PN 110
J 0
(410 4910);
DISPLAY 0.617021 (410 4910);
PAINT ORANGE (410 4910);
FORCEPROP 2 LASTPIN (400 4850) $PN 111
J 0
(410 4860);
DISPLAY 0.617021 (410 4860);
PAINT ORANGE (410 4860);
FORCEPROP 2 LASTPIN (400 4800) $PN 99
J 0
(410 4810);
DISPLAY 0.617021 (410 4810);
PAINT ORANGE (410 4810);
FORCEPROP 2 LASTPIN (400 4750) $PN 100
J 0
(410 4760);
DISPLAY 0.617021 (410 4760);
PAINT ORANGE (410 4760);
FORCEPROP 2 LASTPIN (400 4700) $PN 40
J 0
(410 4710);
DISPLAY 0.617021 (410 4710);
PAINT ORANGE (410 4710);
FORCEPROP 2 LASTPIN (400 4650) $PN 41
J 0
(410 4660);
DISPLAY 0.617021 (410 4660);
PAINT ORANGE (410 4660);
FORCEPROP 2 LASTPIN (400 4600) $PN 29
J 0
(410 4610);
DISPLAY 0.617021 (410 4610);
PAINT ORANGE (410 4610);
FORCEPROP 2 LASTPIN (400 4550) $PN 30
J 0
(410 4560);
DISPLAY 0.617021 (410 4560);
PAINT ORANGE (410 4560);
FORCEPROP 2 LASTPIN (400 4500) $PN 18
J 0
(410 4510);
DISPLAY 0.617021 (410 4510);
PAINT ORANGE (410 4510);
FORCEPROP 2 LASTPIN (400 4450) $PN 19
J 0
(410 4460);
DISPLAY 0.617021 (410 4460);
PAINT ORANGE (410 4460);
FORCEPROP 2 LASTPIN (400 4400) $PN 7
J 0
(410 4410);
DISPLAY 0.617021 (410 4410);
PAINT ORANGE (410 4410);
FORCEPROP 2 LASTPIN (400 4350) $PN 8
J 0
(410 4360);
DISPLAY 0.617021 (410 4360);
PAINT ORANGE (410 4360);
FORCEPROP 2 LASTPIN (400 4300) $PN 197
J 0
(410 4310);
DISPLAY 0.617021 (410 4310);
PAINT ORANGE (410 4310);
FORCEPROP 2 LASTPIN (400 4250) $PN 196
J 0
(410 4260);
DISPLAY 0.617021 (410 4260);
PAINT ORANGE (410 4260);
FORCEPROP 2 LASTPIN (400 4200) $PN 278
J 0
(410 4210);
DISPLAY 0.617021 (410 4210);
PAINT ORANGE (410 4210);
FORCEPROP 2 LASTPIN (400 4150) $PN 277
J 0
(410 4160);
DISPLAY 0.617021 (410 4160);
PAINT ORANGE (410 4160);
FORCEPROP 2 LASTPIN (400 4100) $PN 267
J 0
(410 4110);
DISPLAY 0.617021 (410 4110);
PAINT ORANGE (410 4110);
FORCEPROP 2 LASTPIN (400 4050) $PN 266
J 0
(410 4060);
DISPLAY 0.617021 (410 4060);
PAINT ORANGE (410 4060);
FORCEPROP 2 LASTPIN (400 4000) $PN 256
J 0
(410 4010);
DISPLAY 0.617021 (410 4010);
PAINT ORANGE (410 4010);
FORCEPROP 2 LASTPIN (400 3950) $PN 255
J 0
(410 3960);
DISPLAY 0.617021 (410 3960);
PAINT ORANGE (410 3960);
FORCEPROP 2 LASTPIN (400 3900) $PN 245
J 0
(410 3910);
DISPLAY 0.617021 (410 3910);
PAINT ORANGE (410 3910);
FORCEPROP 2 LASTPIN (400 3850) $PN 244
J 0
(410 3860);
DISPLAY 0.617021 (410 3860);
PAINT ORANGE (410 3860);
FORCEPROP 2 LASTPIN (400 3800) $PN 186
J 0
(410 3810);
DISPLAY 0.617021 (410 3810);
PAINT ORANGE (410 3810);
FORCEPROP 2 LASTPIN (400 3750) $PN 185
J 0
(410 3760);
DISPLAY 0.617021 (410 3760);
PAINT ORANGE (410 3760);
FORCEPROP 2 LASTPIN (400 3700) $PN 175
J 0
(410 3710);
DISPLAY 0.617021 (410 3710);
PAINT ORANGE (410 3710);
FORCEPROP 2 LASTPIN (400 3650) $PN 174
J 0
(410 3660);
DISPLAY 0.617021 (410 3660);
PAINT ORANGE (410 3660);
FORCEPROP 2 LASTPIN (400 3600) $PN 164
J 0
(410 3610);
DISPLAY 0.617021 (410 3610);
PAINT ORANGE (410 3610);
FORCEPROP 2 LASTPIN (400 3550) $PN 163
J 0
(410 3560);
DISPLAY 0.617021 (410 3560);
PAINT ORANGE (410 3560);
FORCEPROP 2 LASTPIN (400 3500) $PN 153
J 0
(410 3510);
DISPLAY 0.617021 (410 3510);
PAINT ORANGE (410 3510);
FORCEPROP 2 LASTPIN (400 3450) $PN 152
J 0
(410 3460);
DISPLAY 0.617021 (410 3460);
PAINT ORANGE (410 3460);
FORCEPROP 1 LAST PART_NUMBER H44441-004
J 0
(-450 3250);
DISPLAY 0.617021 (-450 3250);
PAINT BLUE (-450 3250);
FORCEPROP 1 LAST PACK_TYPE PIP
J 0
(-450 5500);
PAINT SKYBLUE (-450 5500);
DISPLAY INVISIBLE (-450 5500);
FORCEPROP 2 LAST BOM_COST MEM
J 0
(-50 4350);
PAINT ORANGE (-50 4350);
DISPLAY INVISIBLE (-50 4350);
FORCEPROP 2 LAST CDS_LIB mstr_sconn
J 0
(-50 4350);
PAINT ORANGE (-50 4350);
DISPLAY INVISIBLE (-50 4350);
FORCEPROP 2 LAST SEC_TYPE PIP
J 0
(-450 5500);
DISPLAY 1.021277 (-450 5500);
PAINT ORANGE (-450 5500);
DISPLAY INVISIBLE (-450 5500);
FORCEPROP 2 LAST SEC 2
J 0
(-450 5500);
DISPLAY 0.680851 (-450 5500);
PAINT MONO (-450 5500);
DISPLAY INVISIBLE (-450 5500);
FORCEPROP 2 LAST CDS_LOCATION J4A1
J 0
(-450 5450);
DISPLAY 0.617021 (-450 5450);
PAINT AQUA (-450 5450);
DISPLAY INVISIBLE (-450 5450);
FORCEPROP 1 LAST PATH I66
J 0
(-50 5400);
PAINT GREEN (-50 5400);
DISPLAY INVISIBLE (-50 5400);
FORCEPROP 2 LAST ROOM DDR4_CH_F
J 0
(-50 4350);
PAINT ORANGE (-50 4350);
DISPLAY INVISIBLE (-50 4350);
FORCEADD TAP..6
R 2
(-1550 3475);
FORCEPROP 3 LASTPIN (-1600 3475) SIG_NAME M_F_DQ<42>
J 0
(-1590 3485);
DISPLAY 0.659574 (-1590 3485);
PAINT MONO (-1590 3485);
DISPLAY INVISIBLE (-1590 3485);
FORCEPROP 1 LASTPIN (-1600 3475) BN 42
J 2
(-1550 3485);
DISPLAY 0.617021 (-1550 3485);
PAINT PINK (-1550 3485);
FORCEPROP 2 LAST CDS_LIB mstr_standard
J 2
(-1550 3475);
DISPLAY 0.787234 (-1550 3475);
PAINT MONO (-1550 3475);
DISPLAY INVISIBLE (-1550 3475);
FORCEPROP 1 LAST BODY_TYPE PLUMBING
J 2
(-1550 3425);
DISPLAY 1.234043 (-1550 3425);
PAINT GREEN (-1550 3425);
DISPLAY INVISIBLE (-1550 3425);
FORCEPROP 1 LAST HDL_TAP TRUE
J 2
(-1875 3350);
DISPLAY 1.234043 (-1875 3350);
PAINT GREEN (-1875 3350);
DISPLAY INVISIBLE (-1875 3350);
FORCEPROP 1 LAST PATH I67
J 2
(-1550 3475);
DISPLAY 0.936170 (-1550 3475);
PAINT GREEN (-1550 3475);
DISPLAY INVISIBLE (-1550 3475);
FORCEADD TAP..6
R 2
(-1550 3425);
FORCEPROP 3 LASTPIN (-1600 3425) SIG_NAME M_F_DQ<43>
J 0
(-1590 3435);
DISPLAY 0.659574 (-1590 3435);
PAINT MONO (-1590 3435);
DISPLAY INVISIBLE (-1590 3435);
FORCEPROP 1 LASTPIN (-1600 3425) BN 43
J 2
(-1550 3435);
DISPLAY 0.617021 (-1550 3435);
PAINT PINK (-1550 3435);
FORCEPROP 2 LAST CDS_LIB mstr_standard
J 2
(-1550 3425);
DISPLAY 0.787234 (-1550 3425);
PAINT MONO (-1550 3425);
DISPLAY INVISIBLE (-1550 3425);
FORCEPROP 1 LAST BODY_TYPE PLUMBING
J 2
(-1550 3375);
DISPLAY 1.234043 (-1550 3375);
PAINT GREEN (-1550 3375);
DISPLAY INVISIBLE (-1550 3375);
FORCEPROP 1 LAST HDL_TAP TRUE
J 2
(-1875 3300);
DISPLAY 1.234043 (-1875 3300);
PAINT GREEN (-1875 3300);
DISPLAY INVISIBLE (-1875 3300);
FORCEPROP 1 LAST PATH I68
J 2
(-1550 3425);
DISPLAY 0.936170 (-1550 3425);
PAINT GREEN (-1550 3425);
DISPLAY INVISIBLE (-1550 3425);
FORCEADD TAP..6
R 2
(-1550 3325);
FORCEPROP 3 LASTPIN (-1600 3325) SIG_NAME M_F_DQ<41>
J 0
(-1590 3335);
DISPLAY 0.659574 (-1590 3335);
PAINT MONO (-1590 3335);
DISPLAY INVISIBLE (-1590 3335);
FORCEPROP 1 LASTPIN (-1600 3325) BN 41
J 2
(-1550 3335);
DISPLAY 0.617021 (-1550 3335);
PAINT PINK (-1550 3335);
FORCEPROP 2 LAST CDS_LIB mstr_standard
J 2
(-1550 3325);
DISPLAY 0.787234 (-1550 3325);
PAINT MONO (-1550 3325);
DISPLAY INVISIBLE (-1550 3325);
FORCEPROP 1 LAST BODY_TYPE PLUMBING
J 2
(-1550 3275);
DISPLAY 1.234043 (-1550 3275);
PAINT GREEN (-1550 3275);
DISPLAY INVISIBLE (-1550 3275);
FORCEPROP 1 LAST HDL_TAP TRUE
J 2
(-1875 3200);
DISPLAY 1.234043 (-1875 3200);
PAINT GREEN (-1875 3200);
DISPLAY INVISIBLE (-1875 3200);
FORCEPROP 1 LAST PATH I69
J 2
(-1550 3325);
DISPLAY 0.936170 (-1550 3325);
PAINT GREEN (-1550 3325);
DISPLAY INVISIBLE (-1550 3325);
FORCEADD TAP..6
R 2
(850 4750);
FORCEPROP 3 LASTPIN (800 4750) SIG_NAME M_F_DQS_DN<13>
J 0
(810 4760);
DISPLAY 0.659574 (810 4760);
PAINT MONO (810 4760);
DISPLAY INVISIBLE (810 4760);
FORCEPROP 1 LASTPIN (800 4750) BN 13
J 2
(850 4760);
DISPLAY 0.617021 (850 4760);
PAINT PINK (850 4760);
FORCEPROP 2 LAST CDS_LIB mstr_standard
J 0
(850 4750);
DISPLAY 0.787234 (850 4750);
PAINT MONO (850 4750);
DISPLAY INVISIBLE (850 4750);
FORCEPROP 1 LAST BODY_TYPE PLUMBING
J 2
(850 4700);
DISPLAY 1.234043 (850 4700);
PAINT GREEN (850 4700);
DISPLAY INVISIBLE (850 4700);
FORCEPROP 1 LAST HDL_TAP TRUE
J 2
(525 4625);
DISPLAY 1.234043 (525 4625);
PAINT GREEN (525 4625);
DISPLAY INVISIBLE (525 4625);
FORCEPROP 1 LAST PATH I7
J 2
(850 4750);
DISPLAY 0.936170 (850 4750);
PAINT GREEN (850 4750);
DISPLAY INVISIBLE (850 4750);
FORCEADD TAP..6
R 2
(-1550 3275);
FORCEPROP 3 LASTPIN (-1600 3275) SIG_NAME M_F_DQ<38>
J 0
(-1590 3285);
DISPLAY 0.659574 (-1590 3285);
PAINT MONO (-1590 3285);
DISPLAY INVISIBLE (-1590 3285);
FORCEPROP 1 LASTPIN (-1600 3275) BN 38
J 2
(-1550 3285);
DISPLAY 0.617021 (-1550 3285);
PAINT PINK (-1550 3285);
FORCEPROP 2 LAST CDS_LIB mstr_standard
J 2
(-1550 3275);
DISPLAY 0.787234 (-1550 3275);
PAINT MONO (-1550 3275);
DISPLAY INVISIBLE (-1550 3275);
FORCEPROP 1 LAST BODY_TYPE PLUMBING
J 2
(-1550 3225);
DISPLAY 1.234043 (-1550 3225);
PAINT GREEN (-1550 3225);
DISPLAY INVISIBLE (-1550 3225);
FORCEPROP 1 LAST HDL_TAP TRUE
J 2
(-1875 3150);
DISPLAY 1.234043 (-1875 3150);
PAINT GREEN (-1875 3150);
DISPLAY INVISIBLE (-1875 3150);
FORCEPROP 1 LAST PATH I70
J 2
(-1550 3275);
DISPLAY 0.936170 (-1550 3275);
PAINT GREEN (-1550 3275);
DISPLAY INVISIBLE (-1550 3275);
FORCEADD TAP..6
R 2
(-1550 3375);
FORCEPROP 3 LASTPIN (-1600 3375) SIG_NAME M_F_DQ<40>
J 0
(-1590 3385);
DISPLAY 0.659574 (-1590 3385);
PAINT MONO (-1590 3385);
DISPLAY INVISIBLE (-1590 3385);
FORCEPROP 1 LASTPIN (-1600 3375) BN 40
J 2
(-1550 3385);
DISPLAY 0.617021 (-1550 3385);
PAINT PINK (-1550 3385);
FORCEPROP 2 LAST CDS_LIB mstr_standard
J 2
(-1550 3375);
DISPLAY 0.787234 (-1550 3375);
PAINT MONO (-1550 3375);
DISPLAY INVISIBLE (-1550 3375);
FORCEPROP 1 LAST BODY_TYPE PLUMBING
J 2
(-1550 3325);
DISPLAY 1.234043 (-1550 3325);
PAINT GREEN (-1550 3325);
DISPLAY INVISIBLE (-1550 3325);
FORCEPROP 1 LAST HDL_TAP TRUE
J 2
(-1875 3250);
DISPLAY 1.234043 (-1875 3250);
PAINT GREEN (-1875 3250);
DISPLAY INVISIBLE (-1875 3250);
FORCEPROP 1 LAST PATH I71
J 2
(-1550 3375);
DISPLAY 0.936170 (-1550 3375);
PAINT GREEN (-1550 3375);
DISPLAY INVISIBLE (-1550 3375);
FORCEADD TAP..6
R 2
(-1550 3225);
FORCEPROP 3 LASTPIN (-1600 3225) SIG_NAME M_F_DQ<39>
J 0
(-1590 3235);
DISPLAY 0.659574 (-1590 3235);
PAINT MONO (-1590 3235);
DISPLAY INVISIBLE (-1590 3235);
FORCEPROP 1 LASTPIN (-1600 3225) BN 39
J 2
(-1550 3235);
DISPLAY 0.617021 (-1550 3235);
PAINT PINK (-1550 3235);
FORCEPROP 2 LAST CDS_LIB mstr_standard
J 2
(-1550 3225);
DISPLAY 0.787234 (-1550 3225);
PAINT MONO (-1550 3225);
DISPLAY INVISIBLE (-1550 3225);
FORCEPROP 1 LAST BODY_TYPE PLUMBING
J 2
(-1550 3175);
DISPLAY 1.234043 (-1550 3175);
PAINT GREEN (-1550 3175);
DISPLAY INVISIBLE (-1550 3175);
FORCEPROP 1 LAST HDL_TAP TRUE
J 2
(-1875 3100);
DISPLAY 1.234043 (-1875 3100);
PAINT GREEN (-1875 3100);
DISPLAY INVISIBLE (-1875 3100);
FORCEPROP 1 LAST PATH I72
J 2
(-1550 3225);
DISPLAY 0.936170 (-1550 3225);
PAINT GREEN (-1550 3225);
DISPLAY INVISIBLE (-1550 3225);
FORCEADD TAP..6
R 2
(-1550 3175);
FORCEPROP 3 LASTPIN (-1600 3175) SIG_NAME M_F_DQ<36>
J 0
(-1590 3185);
DISPLAY 0.659574 (-1590 3185);
PAINT MONO (-1590 3185);
DISPLAY INVISIBLE (-1590 3185);
FORCEPROP 1 LASTPIN (-1600 3175) BN 36
J 2
(-1550 3185);
DISPLAY 0.617021 (-1550 3185);
PAINT PINK (-1550 3185);
FORCEPROP 2 LAST CDS_LIB mstr_standard
J 2
(-1550 3175);
DISPLAY 0.787234 (-1550 3175);
PAINT MONO (-1550 3175);
DISPLAY INVISIBLE (-1550 3175);
FORCEPROP 1 LAST BODY_TYPE PLUMBING
J 2
(-1550 3125);
DISPLAY 1.234043 (-1550 3125);
PAINT GREEN (-1550 3125);
DISPLAY INVISIBLE (-1550 3125);
FORCEPROP 1 LAST HDL_TAP TRUE
J 2
(-1875 3050);
DISPLAY 1.234043 (-1875 3050);
PAINT GREEN (-1875 3050);
DISPLAY INVISIBLE (-1875 3050);
FORCEPROP 1 LAST PATH I73
J 2
(-1550 3175);
DISPLAY 0.936170 (-1550 3175);
PAINT GREEN (-1550 3175);
DISPLAY INVISIBLE (-1550 3175);
FORCEADD TAP..6
R 2
(-1550 3125);
FORCEPROP 3 LASTPIN (-1600 3125) SIG_NAME M_F_DQ<37>
J 0
(-1590 3135);
DISPLAY 0.659574 (-1590 3135);
PAINT MONO (-1590 3135);
DISPLAY INVISIBLE (-1590 3135);
FORCEPROP 1 LASTPIN (-1600 3125) BN 37
J 2
(-1550 3135);
DISPLAY 0.617021 (-1550 3135);
PAINT PINK (-1550 3135);
FORCEPROP 2 LAST CDS_LIB mstr_standard
J 2
(-1550 3125);
DISPLAY 0.787234 (-1550 3125);
PAINT MONO (-1550 3125);
DISPLAY INVISIBLE (-1550 3125);
FORCEPROP 1 LAST BODY_TYPE PLUMBING
J 2
(-1550 3075);
DISPLAY 1.234043 (-1550 3075);
PAINT GREEN (-1550 3075);
DISPLAY INVISIBLE (-1550 3075);
FORCEPROP 1 LAST HDL_TAP TRUE
J 2
(-1875 3000);
DISPLAY 1.234043 (-1875 3000);
PAINT GREEN (-1875 3000);
DISPLAY INVISIBLE (-1875 3000);
FORCEPROP 1 LAST PATH I74
J 2
(-1550 3125);
DISPLAY 0.936170 (-1550 3125);
PAINT GREEN (-1550 3125);
DISPLAY INVISIBLE (-1550 3125);
FORCEADD TAP..6
R 2
(-1550 3025);
FORCEPROP 3 LASTPIN (-1600 3025) SIG_NAME M_F_DQ<35>
J 0
(-1590 3035);
DISPLAY 0.659574 (-1590 3035);
PAINT MONO (-1590 3035);
DISPLAY INVISIBLE (-1590 3035);
FORCEPROP 1 LASTPIN (-1600 3025) BN 35
J 2
(-1550 3035);
DISPLAY 0.617021 (-1550 3035);
PAINT PINK (-1550 3035);
FORCEPROP 2 LAST CDS_LIB mstr_standard
J 2
(-1550 3025);
DISPLAY 0.787234 (-1550 3025);
PAINT MONO (-1550 3025);
DISPLAY INVISIBLE (-1550 3025);
FORCEPROP 1 LAST BODY_TYPE PLUMBING
J 2
(-1550 2975);
DISPLAY 1.234043 (-1550 2975);
PAINT GREEN (-1550 2975);
DISPLAY INVISIBLE (-1550 2975);
FORCEPROP 1 LAST HDL_TAP TRUE
J 2
(-1875 2900);
DISPLAY 1.234043 (-1875 2900);
PAINT GREEN (-1875 2900);
DISPLAY INVISIBLE (-1875 2900);
FORCEPROP 1 LAST PATH I75
J 2
(-1550 3025);
DISPLAY 0.936170 (-1550 3025);
PAINT GREEN (-1550 3025);
DISPLAY INVISIBLE (-1550 3025);
FORCEADD TAP..6
R 2
(-1550 3075);
FORCEPROP 3 LASTPIN (-1600 3075) SIG_NAME M_F_DQ<34>
J 0
(-1590 3085);
DISPLAY 0.659574 (-1590 3085);
PAINT MONO (-1590 3085);
DISPLAY INVISIBLE (-1590 3085);
FORCEPROP 1 LASTPIN (-1600 3075) BN 34
J 2
(-1550 3085);
DISPLAY 0.617021 (-1550 3085);
PAINT PINK (-1550 3085);
FORCEPROP 2 LAST CDS_LIB mstr_standard
J 2
(-1550 3075);
DISPLAY 0.787234 (-1550 3075);
PAINT MONO (-1550 3075);
DISPLAY INVISIBLE (-1550 3075);
FORCEPROP 1 LAST BODY_TYPE PLUMBING
J 2
(-1550 3025);
DISPLAY 1.234043 (-1550 3025);
PAINT GREEN (-1550 3025);
DISPLAY INVISIBLE (-1550 3025);
FORCEPROP 1 LAST HDL_TAP TRUE
J 2
(-1875 2950);
DISPLAY 1.234043 (-1875 2950);
PAINT GREEN (-1875 2950);
DISPLAY INVISIBLE (-1875 2950);
FORCEPROP 1 LAST PATH I76
J 2
(-1550 3075);
DISPLAY 0.936170 (-1550 3075);
PAINT GREEN (-1550 3075);
DISPLAY INVISIBLE (-1550 3075);
FORCEADD TAP..6
R 2
(-1550 2975);
FORCEPROP 3 LASTPIN (-1600 2975) SIG_NAME M_F_DQ<32>
J 0
(-1590 2985);
DISPLAY 0.659574 (-1590 2985);
PAINT MONO (-1590 2985);
DISPLAY INVISIBLE (-1590 2985);
FORCEPROP 1 LASTPIN (-1600 2975) BN 32
J 2
(-1550 2985);
DISPLAY 0.617021 (-1550 2985);
PAINT PINK (-1550 2985);
FORCEPROP 2 LAST CDS_LIB mstr_standard
J 2
(-1550 2975);
DISPLAY 0.787234 (-1550 2975);
PAINT MONO (-1550 2975);
DISPLAY INVISIBLE (-1550 2975);
FORCEPROP 1 LAST BODY_TYPE PLUMBING
J 2
(-1550 2925);
DISPLAY 1.234043 (-1550 2925);
PAINT GREEN (-1550 2925);
DISPLAY INVISIBLE (-1550 2925);
FORCEPROP 1 LAST HDL_TAP TRUE
J 2
(-1875 2850);
DISPLAY 1.234043 (-1875 2850);
PAINT GREEN (-1875 2850);
DISPLAY INVISIBLE (-1875 2850);
FORCEPROP 1 LAST PATH I77
J 2
(-1550 2975);
DISPLAY 0.936170 (-1550 2975);
PAINT GREEN (-1550 2975);
DISPLAY INVISIBLE (-1550 2975);
FORCEADD TAP..6
R 2
(-1550 2925);
FORCEPROP 3 LASTPIN (-1600 2925) SIG_NAME M_F_DQ<33>
J 0
(-1590 2935);
DISPLAY 0.659574 (-1590 2935);
PAINT MONO (-1590 2935);
DISPLAY INVISIBLE (-1590 2935);
FORCEPROP 1 LASTPIN (-1600 2925) BN 33
J 2
(-1550 2935);
DISPLAY 0.617021 (-1550 2935);
PAINT PINK (-1550 2935);
FORCEPROP 2 LAST CDS_LIB mstr_standard
J 2
(-1550 2925);
DISPLAY 0.787234 (-1550 2925);
PAINT MONO (-1550 2925);
DISPLAY INVISIBLE (-1550 2925);
FORCEPROP 1 LAST BODY_TYPE PLUMBING
J 2
(-1550 2875);
DISPLAY 1.234043 (-1550 2875);
PAINT GREEN (-1550 2875);
DISPLAY INVISIBLE (-1550 2875);
FORCEPROP 1 LAST HDL_TAP TRUE
J 2
(-1875 2800);
DISPLAY 1.234043 (-1875 2800);
PAINT GREEN (-1875 2800);
DISPLAY INVISIBLE (-1875 2800);
FORCEPROP 1 LAST PATH I78
J 2
(-1550 2925);
DISPLAY 0.936170 (-1550 2925);
PAINT GREEN (-1550 2925);
DISPLAY INVISIBLE (-1550 2925);
FORCEADD TAP..6
R 2
(-1550 2775);
FORCEPROP 3 LASTPIN (-1600 2775) SIG_NAME M_F_DQ<28>
J 0
(-1590 2785);
DISPLAY 0.659574 (-1590 2785);
PAINT MONO (-1590 2785);
DISPLAY INVISIBLE (-1590 2785);
FORCEPROP 1 LASTPIN (-1600 2775) BN 28
J 2
(-1550 2785);
DISPLAY 0.617021 (-1550 2785);
PAINT PINK (-1550 2785);
FORCEPROP 2 LAST CDS_LIB mstr_standard
J 2
(-1550 2775);
DISPLAY 0.787234 (-1550 2775);
PAINT MONO (-1550 2775);
DISPLAY INVISIBLE (-1550 2775);
FORCEPROP 1 LAST BODY_TYPE PLUMBING
J 2
(-1550 2725);
DISPLAY 1.234043 (-1550 2725);
PAINT GREEN (-1550 2725);
DISPLAY INVISIBLE (-1550 2725);
FORCEPROP 1 LAST HDL_TAP TRUE
J 2
(-1875 2650);
DISPLAY 1.234043 (-1875 2650);
PAINT GREEN (-1875 2650);
DISPLAY INVISIBLE (-1875 2650);
FORCEPROP 1 LAST PATH I79
J 2
(-1550 2775);
DISPLAY 0.936170 (-1550 2775);
PAINT GREEN (-1550 2775);
DISPLAY INVISIBLE (-1550 2775);
FORCEADD TAP..6
R 2
(850 4850);
FORCEPROP 3 LASTPIN (800 4850) SIG_NAME M_F_DQS_DN<14>
J 0
(810 4860);
DISPLAY 0.659574 (810 4860);
PAINT MONO (810 4860);
DISPLAY INVISIBLE (810 4860);
FORCEPROP 1 LASTPIN (800 4850) BN 14
J 2
(850 4860);
DISPLAY 0.617021 (850 4860);
PAINT PINK (850 4860);
FORCEPROP 2 LAST CDS_LIB mstr_standard
J 0
(850 4850);
DISPLAY 0.787234 (850 4850);
PAINT MONO (850 4850);
DISPLAY INVISIBLE (850 4850);
FORCEPROP 1 LAST BODY_TYPE PLUMBING
J 2
(850 4800);
DISPLAY 1.234043 (850 4800);
PAINT GREEN (850 4800);
DISPLAY INVISIBLE (850 4800);
FORCEPROP 1 LAST HDL_TAP TRUE
J 2
(525 4725);
DISPLAY 1.234043 (525 4725);
PAINT GREEN (525 4725);
DISPLAY INVISIBLE (525 4725);
FORCEPROP 1 LAST PATH I8
J 2
(850 4850);
DISPLAY 0.936170 (850 4850);
PAINT GREEN (850 4850);
DISPLAY INVISIBLE (850 4850);
FORCEADD TAP..6
R 2
(-1550 2875);
FORCEPROP 3 LASTPIN (-1600 2875) SIG_NAME M_F_DQ<30>
J 0
(-1590 2885);
DISPLAY 0.659574 (-1590 2885);
PAINT MONO (-1590 2885);
DISPLAY INVISIBLE (-1590 2885);
FORCEPROP 1 LASTPIN (-1600 2875) BN 30
J 2
(-1550 2885);
DISPLAY 0.617021 (-1550 2885);
PAINT PINK (-1550 2885);
FORCEPROP 2 LAST CDS_LIB mstr_standard
J 2
(-1550 2875);
DISPLAY 0.787234 (-1550 2875);
PAINT MONO (-1550 2875);
DISPLAY INVISIBLE (-1550 2875);
FORCEPROP 1 LAST BODY_TYPE PLUMBING
J 2
(-1550 2825);
DISPLAY 1.234043 (-1550 2825);
PAINT GREEN (-1550 2825);
DISPLAY INVISIBLE (-1550 2825);
FORCEPROP 1 LAST HDL_TAP TRUE
J 2
(-1875 2750);
DISPLAY 1.234043 (-1875 2750);
PAINT GREEN (-1875 2750);
DISPLAY INVISIBLE (-1875 2750);
FORCEPROP 1 LAST PATH I80
J 2
(-1550 2875);
DISPLAY 0.936170 (-1550 2875);
PAINT GREEN (-1550 2875);
DISPLAY INVISIBLE (-1550 2875);
FORCEADD TAP..6
R 2
(-1550 2825);
FORCEPROP 3 LASTPIN (-1600 2825) SIG_NAME M_F_DQ<31>
J 0
(-1590 2835);
DISPLAY 0.659574 (-1590 2835);
PAINT MONO (-1590 2835);
DISPLAY INVISIBLE (-1590 2835);
FORCEPROP 1 LASTPIN (-1600 2825) BN 31
J 2
(-1550 2835);
DISPLAY 0.617021 (-1550 2835);
PAINT PINK (-1550 2835);
FORCEPROP 2 LAST CDS_LIB mstr_standard
J 2
(-1550 2825);
DISPLAY 0.787234 (-1550 2825);
PAINT MONO (-1550 2825);
DISPLAY INVISIBLE (-1550 2825);
FORCEPROP 1 LAST BODY_TYPE PLUMBING
J 2
(-1550 2775);
DISPLAY 1.234043 (-1550 2775);
PAINT GREEN (-1550 2775);
DISPLAY INVISIBLE (-1550 2775);
FORCEPROP 1 LAST HDL_TAP TRUE
J 2
(-1875 2700);
DISPLAY 1.234043 (-1875 2700);
PAINT GREEN (-1875 2700);
DISPLAY INVISIBLE (-1875 2700);
FORCEPROP 1 LAST PATH I81
J 2
(-1550 2825);
DISPLAY 0.936170 (-1550 2825);
PAINT GREEN (-1550 2825);
DISPLAY INVISIBLE (-1550 2825);
FORCEADD TAP..6
R 2
(-1550 2675);
FORCEPROP 3 LASTPIN (-1600 2675) SIG_NAME M_F_DQ<26>
J 0
(-1590 2685);
DISPLAY 0.659574 (-1590 2685);
PAINT MONO (-1590 2685);
DISPLAY INVISIBLE (-1590 2685);
FORCEPROP 1 LASTPIN (-1600 2675) BN 26
J 2
(-1550 2685);
DISPLAY 0.617021 (-1550 2685);
PAINT PINK (-1550 2685);
FORCEPROP 2 LAST CDS_LIB mstr_standard
J 2
(-1550 2675);
DISPLAY 0.787234 (-1550 2675);
PAINT MONO (-1550 2675);
DISPLAY INVISIBLE (-1550 2675);
FORCEPROP 1 LAST BODY_TYPE PLUMBING
J 2
(-1550 2625);
DISPLAY 1.234043 (-1550 2625);
PAINT GREEN (-1550 2625);
DISPLAY INVISIBLE (-1550 2625);
FORCEPROP 1 LAST HDL_TAP TRUE
J 2
(-1875 2550);
DISPLAY 1.234043 (-1875 2550);
PAINT GREEN (-1875 2550);
DISPLAY INVISIBLE (-1875 2550);
FORCEPROP 1 LAST PATH I82
J 2
(-1550 2675);
DISPLAY 0.936170 (-1550 2675);
PAINT GREEN (-1550 2675);
DISPLAY INVISIBLE (-1550 2675);
FORCEADD TAP..6
R 2
(-1550 2725);
FORCEPROP 3 LASTPIN (-1600 2725) SIG_NAME M_F_DQ<29>
J 0
(-1590 2735);
DISPLAY 0.659574 (-1590 2735);
PAINT MONO (-1590 2735);
DISPLAY INVISIBLE (-1590 2735);
FORCEPROP 1 LASTPIN (-1600 2725) BN 29
J 2
(-1550 2735);
DISPLAY 0.617021 (-1550 2735);
PAINT PINK (-1550 2735);
FORCEPROP 2 LAST CDS_LIB mstr_standard
J 2
(-1550 2725);
DISPLAY 0.787234 (-1550 2725);
PAINT MONO (-1550 2725);
DISPLAY INVISIBLE (-1550 2725);
FORCEPROP 1 LAST BODY_TYPE PLUMBING
J 2
(-1550 2675);
DISPLAY 1.234043 (-1550 2675);
PAINT GREEN (-1550 2675);
DISPLAY INVISIBLE (-1550 2675);
FORCEPROP 1 LAST HDL_TAP TRUE
J 2
(-1875 2600);
DISPLAY 1.234043 (-1875 2600);
PAINT GREEN (-1875 2600);
DISPLAY INVISIBLE (-1875 2600);
FORCEPROP 1 LAST PATH I83
J 2
(-1550 2725);
DISPLAY 0.936170 (-1550 2725);
PAINT GREEN (-1550 2725);
DISPLAY INVISIBLE (-1550 2725);
FORCEADD TAP..6
R 2
(-1550 2625);
FORCEPROP 3 LASTPIN (-1600 2625) SIG_NAME M_F_DQ<27>
J 0
(-1590 2635);
DISPLAY 0.659574 (-1590 2635);
PAINT MONO (-1590 2635);
DISPLAY INVISIBLE (-1590 2635);
FORCEPROP 1 LASTPIN (-1600 2625) BN 27
J 2
(-1550 2635);
DISPLAY 0.617021 (-1550 2635);
PAINT PINK (-1550 2635);
FORCEPROP 2 LAST CDS_LIB mstr_standard
J 2
(-1550 2625);
DISPLAY 0.787234 (-1550 2625);
PAINT MONO (-1550 2625);
DISPLAY INVISIBLE (-1550 2625);
FORCEPROP 1 LAST BODY_TYPE PLUMBING
J 2
(-1550 2575);
DISPLAY 1.234043 (-1550 2575);
PAINT GREEN (-1550 2575);
DISPLAY INVISIBLE (-1550 2575);
FORCEPROP 1 LAST HDL_TAP TRUE
J 2
(-1875 2500);
DISPLAY 1.234043 (-1875 2500);
PAINT GREEN (-1875 2500);
DISPLAY INVISIBLE (-1875 2500);
FORCEPROP 1 LAST PATH I84
J 2
(-1550 2625);
DISPLAY 0.936170 (-1550 2625);
PAINT GREEN (-1550 2625);
DISPLAY INVISIBLE (-1550 2625);
FORCEADD TAP..6
R 2
(-1550 2525);
FORCEPROP 3 LASTPIN (-1600 2525) SIG_NAME M_F_DQ<25>
J 0
(-1590 2535);
DISPLAY 0.659574 (-1590 2535);
PAINT MONO (-1590 2535);
DISPLAY INVISIBLE (-1590 2535);
FORCEPROP 1 LASTPIN (-1600 2525) BN 25
J 2
(-1550 2535);
DISPLAY 0.617021 (-1550 2535);
PAINT PINK (-1550 2535);
FORCEPROP 2 LAST CDS_LIB mstr_standard
J 2
(-1550 2525);
DISPLAY 0.787234 (-1550 2525);
PAINT MONO (-1550 2525);
DISPLAY INVISIBLE (-1550 2525);
FORCEPROP 1 LAST BODY_TYPE PLUMBING
J 2
(-1550 2475);
DISPLAY 1.234043 (-1550 2475);
PAINT GREEN (-1550 2475);
DISPLAY INVISIBLE (-1550 2475);
FORCEPROP 1 LAST HDL_TAP TRUE
J 2
(-1875 2400);
DISPLAY 1.234043 (-1875 2400);
PAINT GREEN (-1875 2400);
DISPLAY INVISIBLE (-1875 2400);
FORCEPROP 1 LAST PATH I85
J 2
(-1550 2525);
DISPLAY 0.936170 (-1550 2525);
PAINT GREEN (-1550 2525);
DISPLAY INVISIBLE (-1550 2525);
FORCEADD TAP..6
R 2
(-1550 2575);
FORCEPROP 3 LASTPIN (-1600 2575) SIG_NAME M_F_DQ<24>
J 0
(-1590 2585);
DISPLAY 0.659574 (-1590 2585);
PAINT MONO (-1590 2585);
DISPLAY INVISIBLE (-1590 2585);
FORCEPROP 1 LASTPIN (-1600 2575) BN 24
J 2
(-1550 2585);
DISPLAY 0.617021 (-1550 2585);
PAINT PINK (-1550 2585);
FORCEPROP 2 LAST CDS_LIB mstr_standard
J 2
(-1550 2575);
DISPLAY 0.787234 (-1550 2575);
PAINT MONO (-1550 2575);
DISPLAY INVISIBLE (-1550 2575);
FORCEPROP 1 LAST BODY_TYPE PLUMBING
J 2
(-1550 2525);
DISPLAY 1.234043 (-1550 2525);
PAINT GREEN (-1550 2525);
DISPLAY INVISIBLE (-1550 2525);
FORCEPROP 1 LAST HDL_TAP TRUE
J 2
(-1875 2450);
DISPLAY 1.234043 (-1875 2450);
PAINT GREEN (-1875 2450);
DISPLAY INVISIBLE (-1875 2450);
FORCEPROP 1 LAST PATH I86
J 2
(-1550 2575);
DISPLAY 0.936170 (-1550 2575);
PAINT GREEN (-1550 2575);
DISPLAY INVISIBLE (-1550 2575);
FORCEADD TAP..6
R 2
(-1550 2425);
FORCEPROP 3 LASTPIN (-1600 2425) SIG_NAME M_F_DQ<23>
J 0
(-1590 2435);
DISPLAY 0.659574 (-1590 2435);
PAINT MONO (-1590 2435);
DISPLAY INVISIBLE (-1590 2435);
FORCEPROP 1 LASTPIN (-1600 2425) BN 23
J 2
(-1550 2435);
DISPLAY 0.617021 (-1550 2435);
PAINT PINK (-1550 2435);
FORCEPROP 2 LAST CDS_LIB mstr_standard
J 2
(-1550 2425);
DISPLAY 0.787234 (-1550 2425);
PAINT MONO (-1550 2425);
DISPLAY INVISIBLE (-1550 2425);
FORCEPROP 1 LAST BODY_TYPE PLUMBING
J 2
(-1550 2375);
DISPLAY 1.234043 (-1550 2375);
PAINT GREEN (-1550 2375);
DISPLAY INVISIBLE (-1550 2375);
FORCEPROP 1 LAST HDL_TAP TRUE
J 2
(-1875 2300);
DISPLAY 1.234043 (-1875 2300);
PAINT GREEN (-1875 2300);
DISPLAY INVISIBLE (-1875 2300);
FORCEPROP 1 LAST PATH I87
J 2
(-1550 2425);
DISPLAY 0.936170 (-1550 2425);
PAINT GREEN (-1550 2425);
DISPLAY INVISIBLE (-1550 2425);
FORCEADD TAP..6
R 2
(-1550 2475);
FORCEPROP 3 LASTPIN (-1600 2475) SIG_NAME M_F_DQ<22>
J 0
(-1590 2485);
DISPLAY 0.659574 (-1590 2485);
PAINT MONO (-1590 2485);
DISPLAY INVISIBLE (-1590 2485);
FORCEPROP 1 LASTPIN (-1600 2475) BN 22
J 2
(-1550 2485);
DISPLAY 0.617021 (-1550 2485);
PAINT PINK (-1550 2485);
FORCEPROP 2 LAST CDS_LIB mstr_standard
J 2
(-1550 2475);
DISPLAY 0.787234 (-1550 2475);
PAINT MONO (-1550 2475);
DISPLAY INVISIBLE (-1550 2475);
FORCEPROP 1 LAST BODY_TYPE PLUMBING
J 2
(-1550 2425);
DISPLAY 1.234043 (-1550 2425);
PAINT GREEN (-1550 2425);
DISPLAY INVISIBLE (-1550 2425);
FORCEPROP 1 LAST HDL_TAP TRUE
J 2
(-1875 2350);
DISPLAY 1.234043 (-1875 2350);
PAINT GREEN (-1875 2350);
DISPLAY INVISIBLE (-1875 2350);
FORCEPROP 1 LAST PATH I88
J 2
(-1550 2475);
DISPLAY 0.936170 (-1550 2475);
PAINT GREEN (-1550 2475);
DISPLAY INVISIBLE (-1550 2475);
FORCEADD TAP..6
R 2
(-1550 2375);
FORCEPROP 3 LASTPIN (-1600 2375) SIG_NAME M_F_DQ<20>
J 0
(-1590 2385);
DISPLAY 0.659574 (-1590 2385);
PAINT MONO (-1590 2385);
DISPLAY INVISIBLE (-1590 2385);
FORCEPROP 1 LASTPIN (-1600 2375) BN 20
J 2
(-1550 2385);
DISPLAY 0.617021 (-1550 2385);
PAINT PINK (-1550 2385);
FORCEPROP 2 LAST CDS_LIB mstr_standard
J 2
(-1550 2375);
DISPLAY 0.787234 (-1550 2375);
PAINT MONO (-1550 2375);
DISPLAY INVISIBLE (-1550 2375);
FORCEPROP 1 LAST BODY_TYPE PLUMBING
J 2
(-1550 2325);
DISPLAY 1.234043 (-1550 2325);
PAINT GREEN (-1550 2325);
DISPLAY INVISIBLE (-1550 2325);
FORCEPROP 1 LAST HDL_TAP TRUE
J 2
(-1875 2250);
DISPLAY 1.234043 (-1875 2250);
PAINT GREEN (-1875 2250);
DISPLAY INVISIBLE (-1875 2250);
FORCEPROP 1 LAST PATH I89
J 2
(-1550 2375);
DISPLAY 0.936170 (-1550 2375);
PAINT GREEN (-1550 2375);
DISPLAY INVISIBLE (-1550 2375);
FORCEADD TAP..6
R 2
(850 4650);
FORCEPROP 3 LASTPIN (800 4650) SIG_NAME M_F_DQS_DN<12>
J 0
(810 4660);
DISPLAY 0.659574 (810 4660);
PAINT MONO (810 4660);
DISPLAY INVISIBLE (810 4660);
FORCEPROP 1 LASTPIN (800 4650) BN 12
J 2
(850 4660);
DISPLAY 0.617021 (850 4660);
PAINT PINK (850 4660);
FORCEPROP 2 LAST CDS_LIB mstr_standard
J 0
(850 4650);
DISPLAY 0.787234 (850 4650);
PAINT MONO (850 4650);
DISPLAY INVISIBLE (850 4650);
FORCEPROP 1 LAST BODY_TYPE PLUMBING
J 2
(850 4600);
DISPLAY 1.234043 (850 4600);
PAINT GREEN (850 4600);
DISPLAY INVISIBLE (850 4600);
FORCEPROP 1 LAST HDL_TAP TRUE
J 2
(525 4525);
DISPLAY 1.234043 (525 4525);
PAINT GREEN (525 4525);
DISPLAY INVISIBLE (525 4525);
FORCEPROP 1 LAST PATH I9
J 2
(850 4650);
DISPLAY 0.936170 (850 4650);
PAINT GREEN (850 4650);
DISPLAY INVISIBLE (850 4650);
FORCEADD TAP..6
R 2
(-1550 2325);
FORCEPROP 3 LASTPIN (-1600 2325) SIG_NAME M_F_DQ<21>
J 0
(-1590 2335);
DISPLAY 0.659574 (-1590 2335);
PAINT MONO (-1590 2335);
DISPLAY INVISIBLE (-1590 2335);
FORCEPROP 1 LASTPIN (-1600 2325) BN 21
J 2
(-1550 2335);
DISPLAY 0.617021 (-1550 2335);
PAINT PINK (-1550 2335);
FORCEPROP 2 LAST CDS_LIB mstr_standard
J 2
(-1550 2325);
DISPLAY 0.787234 (-1550 2325);
PAINT MONO (-1550 2325);
DISPLAY INVISIBLE (-1550 2325);
FORCEPROP 1 LAST BODY_TYPE PLUMBING
J 2
(-1550 2275);
DISPLAY 1.234043 (-1550 2275);
PAINT GREEN (-1550 2275);
DISPLAY INVISIBLE (-1550 2275);
FORCEPROP 1 LAST HDL_TAP TRUE
J 2
(-1875 2200);
DISPLAY 1.234043 (-1875 2200);
PAINT GREEN (-1875 2200);
DISPLAY INVISIBLE (-1875 2200);
FORCEPROP 1 LAST PATH I90
J 2
(-1550 2325);
DISPLAY 0.936170 (-1550 2325);
PAINT GREEN (-1550 2325);
DISPLAY INVISIBLE (-1550 2325);
FORCEADD TAP..6
R 2
(-1550 2275);
FORCEPROP 3 LASTPIN (-1600 2275) SIG_NAME M_F_DQ<18>
J 0
(-1590 2285);
DISPLAY 0.659574 (-1590 2285);
PAINT MONO (-1590 2285);
DISPLAY INVISIBLE (-1590 2285);
FORCEPROP 1 LASTPIN (-1600 2275) BN 18
J 2
(-1550 2285);
DISPLAY 0.617021 (-1550 2285);
PAINT PINK (-1550 2285);
FORCEPROP 2 LAST CDS_LIB mstr_standard
J 2
(-1550 2275);
DISPLAY 0.787234 (-1550 2275);
PAINT MONO (-1550 2275);
DISPLAY INVISIBLE (-1550 2275);
FORCEPROP 1 LAST BODY_TYPE PLUMBING
J 2
(-1550 2225);
DISPLAY 1.234043 (-1550 2225);
PAINT GREEN (-1550 2225);
DISPLAY INVISIBLE (-1550 2225);
FORCEPROP 1 LAST HDL_TAP TRUE
J 2
(-1875 2150);
DISPLAY 1.234043 (-1875 2150);
PAINT GREEN (-1875 2150);
DISPLAY INVISIBLE (-1875 2150);
FORCEPROP 1 LAST PATH I91
J 2
(-1550 2275);
DISPLAY 0.936170 (-1550 2275);
PAINT GREEN (-1550 2275);
DISPLAY INVISIBLE (-1550 2275);
FORCEADD TAP..6
R 2
(-1550 2225);
FORCEPROP 3 LASTPIN (-1600 2225) SIG_NAME M_F_DQ<19>
J 0
(-1590 2235);
DISPLAY 0.659574 (-1590 2235);
PAINT MONO (-1590 2235);
DISPLAY INVISIBLE (-1590 2235);
FORCEPROP 1 LASTPIN (-1600 2225) BN 19
J 2
(-1550 2235);
DISPLAY 0.617021 (-1550 2235);
PAINT PINK (-1550 2235);
FORCEPROP 2 LAST CDS_LIB mstr_standard
J 2
(-1550 2225);
DISPLAY 0.787234 (-1550 2225);
PAINT MONO (-1550 2225);
DISPLAY INVISIBLE (-1550 2225);
FORCEPROP 1 LAST BODY_TYPE PLUMBING
J 2
(-1550 2175);
DISPLAY 1.234043 (-1550 2175);
PAINT GREEN (-1550 2175);
DISPLAY INVISIBLE (-1550 2175);
FORCEPROP 1 LAST HDL_TAP TRUE
J 2
(-1875 2100);
DISPLAY 1.234043 (-1875 2100);
PAINT GREEN (-1875 2100);
DISPLAY INVISIBLE (-1875 2100);
FORCEPROP 1 LAST PATH I92
J 2
(-1550 2225);
DISPLAY 0.936170 (-1550 2225);
PAINT GREEN (-1550 2225);
DISPLAY INVISIBLE (-1550 2225);
FORCEADD TAP..6
R 2
(-1550 2125);
FORCEPROP 3 LASTPIN (-1600 2125) SIG_NAME M_F_DQ<17>
J 0
(-1590 2135);
DISPLAY 0.659574 (-1590 2135);
PAINT MONO (-1590 2135);
DISPLAY INVISIBLE (-1590 2135);
FORCEPROP 1 LASTPIN (-1600 2125) BN 17
J 2
(-1550 2135);
DISPLAY 0.617021 (-1550 2135);
PAINT PINK (-1550 2135);
FORCEPROP 2 LAST CDS_LIB mstr_standard
J 2
(-1550 2125);
DISPLAY 0.787234 (-1550 2125);
PAINT MONO (-1550 2125);
DISPLAY INVISIBLE (-1550 2125);
FORCEPROP 1 LAST BODY_TYPE PLUMBING
J 2
(-1550 2075);
DISPLAY 1.234043 (-1550 2075);
PAINT GREEN (-1550 2075);
DISPLAY INVISIBLE (-1550 2075);
FORCEPROP 1 LAST HDL_TAP TRUE
J 2
(-1875 2000);
DISPLAY 1.234043 (-1875 2000);
PAINT GREEN (-1875 2000);
DISPLAY INVISIBLE (-1875 2000);
FORCEPROP 1 LAST PATH I93
J 2
(-1550 2125);
DISPLAY 0.936170 (-1550 2125);
PAINT GREEN (-1550 2125);
DISPLAY INVISIBLE (-1550 2125);
FORCEADD TAP..6
R 2
(-1550 2175);
FORCEPROP 3 LASTPIN (-1600 2175) SIG_NAME M_F_DQ<16>
J 0
(-1590 2185);
DISPLAY 0.659574 (-1590 2185);
PAINT MONO (-1590 2185);
DISPLAY INVISIBLE (-1590 2185);
FORCEPROP 1 LASTPIN (-1600 2175) BN 16
J 2
(-1550 2185);
DISPLAY 0.617021 (-1550 2185);
PAINT PINK (-1550 2185);
FORCEPROP 2 LAST CDS_LIB mstr_standard
J 2
(-1550 2175);
DISPLAY 0.787234 (-1550 2175);
PAINT MONO (-1550 2175);
DISPLAY INVISIBLE (-1550 2175);
FORCEPROP 1 LAST BODY_TYPE PLUMBING
J 2
(-1550 2125);
DISPLAY 1.234043 (-1550 2125);
PAINT GREEN (-1550 2125);
DISPLAY INVISIBLE (-1550 2125);
FORCEPROP 1 LAST HDL_TAP TRUE
J 2
(-1875 2050);
DISPLAY 1.234043 (-1875 2050);
PAINT GREEN (-1875 2050);
DISPLAY INVISIBLE (-1875 2050);
FORCEPROP 1 LAST PATH I94
J 2
(-1550 2175);
DISPLAY 0.936170 (-1550 2175);
PAINT GREEN (-1550 2175);
DISPLAY INVISIBLE (-1550 2175);
FORCEADD TAP..6
R 2
(-1550 2075);
FORCEPROP 3 LASTPIN (-1600 2075) SIG_NAME M_F_DQ<14>
J 0
(-1590 2085);
DISPLAY 0.659574 (-1590 2085);
PAINT MONO (-1590 2085);
DISPLAY INVISIBLE (-1590 2085);
FORCEPROP 1 LASTPIN (-1600 2075) BN 14
J 2
(-1550 2085);
DISPLAY 0.617021 (-1550 2085);
PAINT PINK (-1550 2085);
FORCEPROP 2 LAST CDS_LIB mstr_standard
J 2
(-1550 2075);
DISPLAY 0.787234 (-1550 2075);
PAINT MONO (-1550 2075);
DISPLAY INVISIBLE (-1550 2075);
FORCEPROP 1 LAST BODY_TYPE PLUMBING
J 2
(-1550 2025);
DISPLAY 1.234043 (-1550 2025);
PAINT GREEN (-1550 2025);
DISPLAY INVISIBLE (-1550 2025);
FORCEPROP 1 LAST HDL_TAP TRUE
J 2
(-1875 1950);
DISPLAY 1.234043 (-1875 1950);
PAINT GREEN (-1875 1950);
DISPLAY INVISIBLE (-1875 1950);
FORCEPROP 1 LAST PATH I95
J 2
(-1550 2075);
DISPLAY 0.936170 (-1550 2075);
PAINT GREEN (-1550 2075);
DISPLAY INVISIBLE (-1550 2075);
FORCEADD TAP..6
R 2
(-1550 2025);
FORCEPROP 3 LASTPIN (-1600 2025) SIG_NAME M_F_DQ<15>
J 0
(-1590 2035);
DISPLAY 0.659574 (-1590 2035);
PAINT MONO (-1590 2035);
DISPLAY INVISIBLE (-1590 2035);
FORCEPROP 1 LASTPIN (-1600 2025) BN 15
J 2
(-1550 2035);
DISPLAY 0.617021 (-1550 2035);
PAINT PINK (-1550 2035);
FORCEPROP 2 LAST CDS_LIB mstr_standard
J 2
(-1550 2025);
DISPLAY 0.787234 (-1550 2025);
PAINT MONO (-1550 2025);
DISPLAY INVISIBLE (-1550 2025);
FORCEPROP 1 LAST BODY_TYPE PLUMBING
J 2
(-1550 1975);
DISPLAY 1.234043 (-1550 1975);
PAINT GREEN (-1550 1975);
DISPLAY INVISIBLE (-1550 1975);
FORCEPROP 1 LAST HDL_TAP TRUE
J 2
(-1875 1900);
DISPLAY 1.234043 (-1875 1900);
PAINT GREEN (-1875 1900);
DISPLAY INVISIBLE (-1875 1900);
FORCEPROP 1 LAST PATH I96
J 2
(-1550 2025);
DISPLAY 0.936170 (-1550 2025);
PAINT GREEN (-1550 2025);
DISPLAY INVISIBLE (-1550 2025);
FORCEADD TAP..6
R 2
(-1550 1925);
FORCEPROP 3 LASTPIN (-1600 1925) SIG_NAME M_F_DQ<13>
J 0
(-1590 1935);
DISPLAY 0.659574 (-1590 1935);
PAINT MONO (-1590 1935);
DISPLAY INVISIBLE (-1590 1935);
FORCEPROP 1 LASTPIN (-1600 1925) BN 13
J 2
(-1550 1935);
DISPLAY 0.617021 (-1550 1935);
PAINT PINK (-1550 1935);
FORCEPROP 2 LAST CDS_LIB mstr_standard
J 2
(-1550 1925);
DISPLAY 0.787234 (-1550 1925);
PAINT MONO (-1550 1925);
DISPLAY INVISIBLE (-1550 1925);
FORCEPROP 1 LAST BODY_TYPE PLUMBING
J 2
(-1550 1875);
DISPLAY 1.234043 (-1550 1875);
PAINT GREEN (-1550 1875);
DISPLAY INVISIBLE (-1550 1875);
FORCEPROP 1 LAST HDL_TAP TRUE
J 2
(-1875 1800);
DISPLAY 1.234043 (-1875 1800);
PAINT GREEN (-1875 1800);
DISPLAY INVISIBLE (-1875 1800);
FORCEPROP 1 LAST PATH I97
J 2
(-1550 1925);
DISPLAY 0.936170 (-1550 1925);
PAINT GREEN (-1550 1925);
DISPLAY INVISIBLE (-1550 1925);
FORCEADD TAP..6
R 2
(-1550 1975);
FORCEPROP 3 LASTPIN (-1600 1975) SIG_NAME M_F_DQ<12>
J 0
(-1590 1985);
DISPLAY 0.659574 (-1590 1985);
PAINT MONO (-1590 1985);
DISPLAY INVISIBLE (-1590 1985);
FORCEPROP 1 LASTPIN (-1600 1975) BN 12
J 2
(-1550 1985);
DISPLAY 0.617021 (-1550 1985);
PAINT PINK (-1550 1985);
FORCEPROP 2 LAST CDS_LIB mstr_standard
J 2
(-1550 1975);
DISPLAY 0.787234 (-1550 1975);
PAINT MONO (-1550 1975);
DISPLAY INVISIBLE (-1550 1975);
FORCEPROP 1 LAST BODY_TYPE PLUMBING
J 2
(-1550 1925);
DISPLAY 1.234043 (-1550 1925);
PAINT GREEN (-1550 1925);
DISPLAY INVISIBLE (-1550 1925);
FORCEPROP 1 LAST HDL_TAP TRUE
J 2
(-1875 1850);
DISPLAY 1.234043 (-1875 1850);
PAINT GREEN (-1875 1850);
DISPLAY INVISIBLE (-1875 1850);
FORCEPROP 1 LAST PATH I98
J 2
(-1550 1975);
DISPLAY 0.936170 (-1550 1975);
PAINT GREEN (-1550 1975);
DISPLAY INVISIBLE (-1550 1975);
FORCEADD TAP..6
R 2
(-1550 1875);
FORCEPROP 3 LASTPIN (-1600 1875) SIG_NAME M_F_DQ<10>
J 0
(-1590 1885);
DISPLAY 0.659574 (-1590 1885);
PAINT MONO (-1590 1885);
DISPLAY INVISIBLE (-1590 1885);
FORCEPROP 1 LASTPIN (-1600 1875) BN 10
J 2
(-1550 1885);
DISPLAY 0.617021 (-1550 1885);
PAINT PINK (-1550 1885);
FORCEPROP 2 LAST CDS_LIB mstr_standard
J 2
(-1550 1875);
DISPLAY 0.787234 (-1550 1875);
PAINT MONO (-1550 1875);
DISPLAY INVISIBLE (-1550 1875);
FORCEPROP 1 LAST BODY_TYPE PLUMBING
J 2
(-1550 1825);
DISPLAY 1.234043 (-1550 1825);
PAINT GREEN (-1550 1825);
DISPLAY INVISIBLE (-1550 1825);
FORCEPROP 1 LAST HDL_TAP TRUE
J 2
(-1875 1750);
DISPLAY 1.234043 (-1875 1750);
PAINT GREEN (-1875 1750);
DISPLAY INVISIBLE (-1875 1750);
FORCEPROP 1 LAST PATH I99
J 2
(-1550 1875);
DISPLAY 0.936170 (-1550 1875);
PAINT GREEN (-1550 1875);
DISPLAY INVISIBLE (-1550 1875);
FORCEADD INTEL_CORP_BPAGE..1
(2650 500);
FORCEPROP 1 LAST CDS_CON_LAST_MODIFIED Fri Jun 16 17:48:21 2017
J 0
(1225 825);
DISPLAY 0.787234 (1225 825);
PAINT ORANGE (1225 825);
DISPLAY INVISIBLE (1225 825);
FORCEPROP 1 LAST CUSTOM_TXT_CDS <CURRENT_DESIGN_SHEET> OF <TOTAL_DESIGN_SHEETS>
J 0
(2150 525);
PAINT ORANGE (2150 525);
FORCEPROP 2 LAST CUSTOM_TXT_CDS <XR_PAGE_TITLE>
J 0
(-5240 5750);
DISPLAY 0.638298 (-5240 5750);
PAINT PINK (-5240 5750);
DISPLAY INVISIBLE (-5240 5750);
FORCEPROP 2 LAST CUSTOM_TXT_CDS <CON_LAST_MODIFIED>
J 0
(-1350 600);
DISPLAY 1.042553 (-1350 600);
PAINT ORANGE (-1350 600);
FORCEPROP 1 LAST SCH_TITLE CPU0 DDR4 CH F DIMM0
J 0
(-5275 550);
DISPLAY 1.212766 (-5275 550);
PAINT WHITE (-5275 550);
FORCEPROP 2 LAST PAGE_BORDER TRUE
J 0
(-5240 5750);
DISPLAY 0.680851 (-5240 5750);
PAINT PINK (-5240 5750);
DISPLAY INVISIBLE (-5240 5750);
FORCEPROP 2 LAST CDS_LIB mstr_symbols
J 0
(2650 500);
DISPLAY 0.787234 (2650 500);
PAINT MONO (2650 500);
DISPLAY INVISIBLE (2650 500);
FORCEPROP 1 LAST COMMENT_BODY TRUE
J 0
(2660 510);
DISPLAY 0.382979 (2660 510);
PAINT GREEN (2660 510);
DISPLAY INVISIBLE (2660 510);
FORCEPROP 2 LAST CDS_XR_PAGE_TITLE CR-53 : @BASEBOARD_FAB2_LIB.BASEBOARD_FAB2(SCH_1):PAGE53
J 0
(-5240 5750);
DISPLAY 0.638298 (-5240 5750);
PAINT PINK (-5240 5750);
DISPLAY INVISIBLE (-5240 5750);
FORCEADD BOM_NOTE..1
(-5075 5275);
FORCEPROP 0 LAST L1 STUFF FOR SKU A & B
J 0
(-5225 5175);
DISPLAY 1.063830 (-5225 5175);
PAINT WHITE (-5225 5175);
FORCEPROP 2 LAST CDS_LIB mstr_symbols
J 0
(-5075 5275);
PAINT ORANGE (-5075 5275);
DISPLAY INVISIBLE (-5075 5275);
FORCEPROP 2 LAST BOM_COST SB
J 0
(-5225 5250);
DISPLAY 1.361702 (-5225 5250);
PAINT ORANGE (-5225 5250);
DISPLAY INVISIBLE (-5225 5250);
FORCEPROP 1 LAST COMMENT_BODY TRUE
J 0
(-5050 5375);
DISPLAY 1.319149 (-5050 5375);
PAINT ORANGE (-5050 5375);
DISPLAY INVISIBLE (-5050 5375);
FORCEPROP 2 LAST ROOM SB_HEADERS
J 0
(-5225 5250);
DISPLAY 1.361702 (-5225 5250);
PAINT ORANGE (-5225 5250);
DISPLAY INVISIBLE (-5225 5250);
WIRE 16 -1 (-1100 2700)(-1100 2600);
WIRE 16 -1 (-1100 2600)(-950 2600);
WIRE 16 -1 (-950 2550)(-950 2600);
WIRE 16 -1 (-950 2600)(-750 2600);
WIRE 16 -1 (-950 2550)(-750 2550);
WIRE 16 -1 (-1275 2450)(-1275 2550);
WIRE 16 -1 (-1275 2450)(-900 2450);
WIRE 16 -1 (-900 2400)(-900 2450);
WIRE 16 -1 (-900 2450)(-750 2450);
WIRE 16 -1 (-900 2350)(-900 2400);
WIRE 16 -1 (-900 2400)(-750 2400);
WIRE 16 -1 (-900 2300)(-900 2350);
WIRE 16 -1 (-900 2350)(-750 2350);
WIRE 16 -1 (-900 2250)(-900 2300);
WIRE 16 -1 (-900 2300)(-750 2300);
WIRE 16 -1 (-900 2200)(-900 2250);
WIRE 16 -1 (-900 2250)(-750 2250);
WIRE 16 -1 (-900 2150)(-900 2200);
WIRE 16 -1 (-900 2200)(-750 2200);
WIRE 16 -1 (-900 2100)(-900 2150);
WIRE 16 -1 (-900 2150)(-750 2150);
WIRE 16 -1 (-900 2050)(-900 2100);
WIRE 16 -1 (-900 2100)(-750 2100);
WIRE 16 -1 (-900 2000)(-900 2050);
WIRE 16 -1 (-900 2050)(-750 2050);
WIRE 16 -1 (-900 1950)(-900 2000);
WIRE 16 -1 (-900 2000)(-750 2000);
WIRE 16 -1 (-900 1900)(-900 1950);
WIRE 16 -1 (-900 1950)(-750 1950);
WIRE 16 -1 (-900 1850)(-900 1900);
WIRE 16 -1 (-900 1900)(-750 1900);
WIRE 16 -1 (-900 1800)(-900 1850);
WIRE 16 -1 (-900 1850)(-750 1850);
WIRE 16 -1 (-900 1750)(-900 1800);
WIRE 16 -1 (-900 1800)(-750 1800);
WIRE 16 -1 (-900 1700)(-900 1750);
WIRE 16 -1 (-900 1750)(-750 1750);
WIRE 16 -1 (-900 1650)(-900 1700);
WIRE 16 -1 (-900 1700)(-750 1700);
WIRE 16 -1 (-900 1600)(-900 1650);
WIRE 16 -1 (-900 1650)(-750 1650);
WIRE 16 -1 (-900 1550)(-900 1600);
WIRE 16 -1 (-900 1600)(-750 1600);
WIRE 16 -1 (-900 1500)(-900 1550);
WIRE 16 -1 (-900 1550)(-750 1550);
WIRE 16 -1 (-900 1450)(-900 1500);
WIRE 16 -1 (-900 1500)(-750 1500);
WIRE 16 -1 (-900 1400)(-900 1450);
WIRE 16 -1 (-900 1450)(-750 1450);
WIRE 16 -1 (-900 1350)(-900 1400);
WIRE 16 -1 (-900 1400)(-750 1400);
WIRE 16 -1 (-900 1300)(-900 1350);
WIRE 16 -1 (-900 1350)(-750 1350);
WIRE 16 -1 (-900 1300)(-900 1250);
WIRE 16 -1 (-900 1300)(-750 1300);
WIRE 16 -1 (-900 1250)(-900 1200);
WIRE 16 -1 (-900 1250)(-750 1250);
WIRE 16 -1 (-750 1200)(-900 1200);
WIRE 16 -1 (2450 1150)(2450 1250);
WIRE 16 -1 (2450 1250)(2450 1300);
WIRE 16 -1 (2450 1250)(2250 1250);
WIRE 16 -1 (2450 1300)(2450 1350);
WIRE 16 -1 (2450 1300)(2250 1300);
WIRE 16 -1 (2450 1350)(2450 1400);
WIRE 16 -1 (2450 1350)(2250 1350);
WIRE 16 -1 (2450 1400)(2450 1450);
WIRE 16 -1 (2450 1400)(2250 1400);
WIRE 16 -1 (2450 1450)(2450 1500);
WIRE 16 -1 (2450 1450)(2250 1450);
WIRE 16 -1 (2450 1500)(2450 1550);
WIRE 16 -1 (2450 1500)(2250 1500);
WIRE 16 -1 (2450 1550)(2450 1600);
WIRE 16 -1 (2450 1550)(2250 1550);
WIRE 16 -1 (2450 1600)(2450 1650);
WIRE 16 -1 (2450 1600)(2250 1600);
WIRE 16 -1 (2450 1650)(2450 1700);
WIRE 16 -1 (2450 1650)(2250 1650);
WIRE 16 -1 (2450 1700)(2450 1750);
WIRE 16 -1 (2450 1700)(2250 1700);
WIRE 16 -1 (2450 1750)(2450 1800);
WIRE 16 -1 (2450 1750)(2250 1750);
WIRE 16 -1 (2450 1800)(2450 1850);
WIRE 16 -1 (2450 1800)(2250 1800);
WIRE 16 -1 (2450 1850)(2450 1900);
WIRE 16 -1 (2450 1850)(2250 1850);
WIRE 16 -1 (2450 1900)(2450 1950);
WIRE 16 -1 (2450 1900)(2250 1900);
WIRE 16 -1 (2450 1950)(2450 2000);
WIRE 16 -1 (2450 1950)(2250 1950);
WIRE 16 -1 (2450 2000)(2450 2050);
WIRE 16 -1 (2450 2000)(2250 2000);
WIRE 16 -1 (2450 2050)(2450 2100);
WIRE 16 -1 (2450 2050)(2250 2050);
WIRE 16 -1 (2450 2100)(2450 2150);
WIRE 16 -1 (2450 2100)(2250 2100);
WIRE 16 -1 (2450 2150)(2450 2200);
WIRE 16 -1 (2450 2150)(2250 2150);
WIRE 16 -1 (2450 2200)(2450 2250);
WIRE 16 -1 (2450 2200)(2250 2200);
WIRE 16 -1 (2450 2250)(2450 2300);
WIRE 16 -1 (2450 2250)(2250 2250);
WIRE 16 -1 (2450 2300)(2450 2350);
WIRE 16 -1 (2450 2300)(2250 2300);
WIRE 16 -1 (2450 2350)(2450 2400);
WIRE 16 -1 (2450 2350)(2250 2350);
WIRE 16 -1 (2450 2400)(2450 2450);
WIRE 16 -1 (2450 2400)(2250 2400);
WIRE 16 -1 (2450 2450)(2450 2500);
WIRE 16 -1 (2450 2450)(2250 2450);
WIRE 16 -1 (2450 2500)(2450 2550);
WIRE 16 -1 (2450 2500)(2250 2500);
WIRE 16 -1 (2450 2550)(2450 2600);
WIRE 16 -1 (2450 2550)(2250 2550);
WIRE 16 -1 (2450 2600)(2450 2650);
WIRE 16 -1 (2450 2600)(2250 2600);
WIRE 16 -1 (2450 2650)(2450 2700);
WIRE 16 -1 (2450 2650)(2250 2650);
WIRE 16 -1 (2450 2700)(2450 2750);
WIRE 16 -1 (2450 2700)(2250 2700);
WIRE 16 -1 (2450 2750)(2450 2800);
WIRE 16 -1 (2450 2750)(2250 2750);
WIRE 16 -1 (2450 2800)(2450 2850);
WIRE 16 -1 (2450 2800)(2250 2800);
WIRE 16 -1 (2450 2850)(2450 2900);
WIRE 16 -1 (2450 2850)(2250 2850);
WIRE 16 -1 (2450 2900)(2450 2950);
WIRE 16 -1 (2450 2900)(2250 2900);
WIRE 16 -1 (2450 2950)(2450 3000);
WIRE 16 -1 (2450 2950)(2250 2950);
WIRE 16 -1 (2450 3000)(2450 3050);
WIRE 16 -1 (2450 3000)(2250 3000);
WIRE 16 -1 (2450 3050)(2450 3100);
WIRE 16 -1 (2450 3050)(2250 3050);
WIRE 16 -1 (2450 3100)(2450 3150);
WIRE 16 -1 (2450 3100)(2250 3100);
WIRE 16 -1 (2450 3150)(2450 3200);
WIRE 16 -1 (2450 3150)(2250 3150);
WIRE 16 -1 (2450 3200)(2450 3250);
WIRE 16 -1 (2450 3200)(2250 3200);
WIRE 16 -1 (2450 3250)(2450 3300);
WIRE 16 -1 (2450 3250)(2250 3250);
WIRE 16 -1 (2450 3300)(2450 3350);
WIRE 16 -1 (2450 3300)(2250 3300);
WIRE 16 -1 (2450 3350)(2450 3400);
WIRE 16 -1 (2450 3350)(2250 3350);
WIRE 16 -1 (2450 3400)(2450 3450);
WIRE 16 -1 (2450 3400)(2250 3400);
WIRE 16 -1 (2450 3450)(2450 3500);
WIRE 16 -1 (2450 3450)(2250 3450);
WIRE 16 -1 (2450 3500)(2450 3550);
WIRE 16 -1 (2450 3500)(2250 3500);
WIRE 16 -1 (2450 3550)(2250 3550);
WIRE 16 -1 (-5050 1525)(-5050 1575);
WIRE 16 -1 (-3025 1575)(-5050 1575);
WIRE 16 -1 (-3025 1525)(-3025 1575);
WIRE 16 -1 (-2800 1575)(-3025 1575);
WIRE 16 -1 (-2800 1525)(-3025 1525);
WIRE 16 -1 (-4500 1025)(-4500 925);
WIRE 16 -1 (-950 3000)(-950 2900);
WIRE 16 -1 (-950 2850)(-950 2900);
WIRE 16 -1 (-950 2900)(-750 2900);
WIRE 16 -1 (-950 2850)(-950 2800);
WIRE 16 -1 (-950 2850)(-750 2850);
WIRE 16 -1 (-950 2800)(-950 2750);
WIRE 16 -1 (-750 2800)(-950 2800);
WIRE 16 -1 (-950 2750)(-950 2700);
WIRE 16 -1 (-950 2750)(-750 2750);
WIRE 16 -1 (-950 2700)(-750 2700);
WIRE 16 -1 (-5050 1775)(-5050 1675);
WIRE 16 -1 (-3025 1675)(-5050 1675);
WIRE 16 -1 (-3025 1625)(-3025 1675);
WIRE 16 -1 (-2800 1675)(-3025 1675);
WIRE 16 -1 (-2800 1625)(-3025 1625);
WIRE 16 -1 (450 3075)(450 2900);
WIRE 16 -1 (450 2850)(450 2900);
WIRE 16 -1 (250 2900)(450 2900);
WIRE 16 -1 (250 2850)(450 2850);
WIRE 16 -1 (1050 1125)(1050 1250);
WIRE 16 -1 (1050 1250)(1050 1300);
WIRE 16 -1 (1050 1250)(1250 1250);
WIRE 16 -1 (1050 1300)(1050 1350);
WIRE 16 -1 (1050 1300)(1250 1300);
WIRE 16 -1 (1050 1350)(1050 1400);
WIRE 16 -1 (1050 1350)(1250 1350);
WIRE 16 -1 (1050 1400)(1050 1450);
WIRE 16 -1 (1050 1400)(1250 1400);
WIRE 16 -1 (1050 1450)(1050 1500);
WIRE 16 -1 (1050 1450)(1250 1450);
WIRE 16 -1 (1050 1500)(1050 1550);
WIRE 16 -1 (1050 1500)(1250 1500);
WIRE 16 -1 (1050 1550)(1050 1600);
WIRE 16 -1 (1050 1550)(1250 1550);
WIRE 16 -1 (1050 1600)(1050 1650);
WIRE 16 -1 (1050 1600)(1250 1600);
WIRE 16 -1 (1050 1650)(1050 1700);
WIRE 16 -1 (1050 1650)(1250 1650);
WIRE 16 -1 (1050 1700)(1050 1750);
WIRE 16 -1 (1050 1700)(1250 1700);
WIRE 16 -1 (1050 1750)(1050 1800);
WIRE 16 -1 (1050 1750)(1250 1750);
WIRE 16 -1 (1050 1800)(1050 1850);
WIRE 16 -1 (1050 1800)(1250 1800);
WIRE 16 -1 (1050 1850)(1050 1900);
WIRE 16 -1 (1050 1850)(1250 1850);
WIRE 16 -1 (1050 1900)(1050 1950);
WIRE 16 -1 (1050 1900)(1250 1900);
WIRE 16 -1 (1050 1950)(1050 2000);
WIRE 16 -1 (1050 1950)(1250 1950);
WIRE 16 -1 (1050 2000)(1050 2050);
WIRE 16 -1 (1050 2000)(1250 2000);
WIRE 16 -1 (1050 2050)(1050 2100);
WIRE 16 -1 (1050 2050)(1250 2050);
WIRE 16 -1 (1050 2100)(1050 2150);
WIRE 16 -1 (1050 2100)(1250 2100);
WIRE 16 -1 (1050 2150)(1050 2200);
WIRE 16 -1 (1050 2150)(1250 2150);
WIRE 16 -1 (1050 2200)(1050 2250);
WIRE 16 -1 (1050 2200)(1250 2200);
WIRE 16 -1 (1050 2250)(1050 2300);
WIRE 16 -1 (1050 2250)(1250 2250);
WIRE 16 -1 (1050 2300)(1050 2350);
WIRE 16 -1 (1050 2300)(1250 2300);
WIRE 16 -1 (1050 2350)(1050 2400);
WIRE 16 -1 (1050 2350)(1250 2350);
WIRE 16 -1 (1050 2400)(1050 2450);
WIRE 16 -1 (1050 2400)(1250 2400);
WIRE 16 -1 (1050 2450)(1050 2500);
WIRE 16 -1 (1050 2450)(1250 2450);
WIRE 16 -1 (1050 2500)(1050 2550);
WIRE 16 -1 (1050 2500)(1250 2500);
WIRE 16 -1 (1050 2550)(1050 2600);
WIRE 16 -1 (1050 2550)(1250 2550);
WIRE 16 -1 (1050 2600)(1050 2650);
WIRE 16 -1 (1050 2600)(1250 2600);
WIRE 16 -1 (1050 2650)(1050 2700);
WIRE 16 -1 (1050 2650)(1250 2650);
WIRE 16 -1 (1050 2700)(1050 2750);
WIRE 16 -1 (1050 2700)(1250 2700);
WIRE 16 -1 (1050 2750)(1050 2800);
WIRE 16 -1 (1050 2750)(1250 2750);
WIRE 16 -1 (1050 2800)(1050 2850);
WIRE 16 -1 (1050 2800)(1250 2800);
WIRE 16 -1 (1050 2850)(1050 2900);
WIRE 16 -1 (1050 2850)(1250 2850);
WIRE 16 -1 (1050 2900)(1050 2950);
WIRE 16 -1 (1050 2900)(1250 2900);
WIRE 16 -1 (1050 2950)(1050 3000);
WIRE 16 -1 (1050 2950)(1250 2950);
WIRE 16 -1 (1050 3000)(1050 3050);
WIRE 16 -1 (1050 3000)(1250 3000);
WIRE 16 -1 (1050 3050)(1050 3100);
WIRE 16 -1 (1050 3050)(1250 3050);
WIRE 16 -1 (1050 3100)(1050 3150);
WIRE 16 -1 (1050 3100)(1250 3100);
WIRE 16 -1 (1050 3150)(1050 3200);
WIRE 16 -1 (1050 3150)(1250 3150);
WIRE 16 -1 (1050 3200)(1050 3250);
WIRE 16 -1 (1050 3200)(1250 3200);
WIRE 16 -1 (1050 3250)(1050 3300);
WIRE 16 -1 (1050 3250)(1250 3250);
WIRE 16 -1 (1050 3300)(1050 3350);
WIRE 16 -1 (1050 3300)(1250 3300);
WIRE 16 -1 (1050 3350)(1050 3400);
WIRE 16 -1 (1050 3350)(1250 3350);
WIRE 16 -1 (1050 3400)(1050 3450);
WIRE 16 -1 (1050 3400)(1250 3400);
WIRE 16 -1 (1050 3450)(1050 3500);
WIRE 16 -1 (1050 3450)(1250 3450);
WIRE 16 -1 (1050 3500)(1050 3550);
WIRE 16 -1 (1050 3500)(1250 3500);
WIRE 16 -1 (1050 3550)(1250 3550);
WIRE 17 -1 (900 3475)(900 3575);
WIRE 17 -1 (900 3575)(900 3675);
WIRE 17 -1 (900 3675)(900 3775);
WIRE 17 -1 (900 3775)(900 3875);
WIRE 17 -1 (900 3875)(900 3975);
WIRE 17 -1 (900 3975)(900 4075);
WIRE 17 -1 (900 4075)(900 4175);
WIRE 17 -1 (900 4175)(900 4275);
WIRE 17 -1 (900 4275)(900 4375);
WIRE 17 -1 (900 4375)(900 4475);
WIRE 17 -1 (900 4475)(900 4575);
WIRE 17 -1 (900 4575)(900 4675);
WIRE 17 -1 (900 4675)(900 4775);
WIRE 17 -1 (900 4775)(900 4875);
WIRE 17 -1 (900 4875)(900 4975);
WIRE 17 -1 (900 4975)(900 5075);
WIRE 17 -1 (900 5075)(900 5175);
WIRE 17 -1 (1500 5200)(900 5200);
FORCEPROP 2 LAST SIG_NAME M_F_DQS_DN<17:0>
J 0
(925 5210);
DISPLAY 0.617021 (925 5210);
PAINT ORANGE (925 5210);
WIRE 17 -1 (900 5200)(900 5175);
WIRE 17 -1 (700 3525)(700 3625);
WIRE 17 -1 (700 3625)(700 3725);
WIRE 17 -1 (700 3725)(700 3825);
WIRE 17 -1 (700 3825)(700 3925);
WIRE 17 -1 (700 3925)(700 4025);
WIRE 17 -1 (700 4025)(700 4125);
WIRE 17 -1 (700 4125)(700 4225);
WIRE 17 -1 (700 4225)(700 4325);
WIRE 17 -1 (700 4325)(700 4425);
WIRE 17 -1 (700 4425)(700 4525);
WIRE 17 -1 (700 4525)(700 4625);
WIRE 17 -1 (700 4625)(700 4725);
WIRE 17 -1 (700 4725)(700 4825);
WIRE 17 -1 (700 4825)(700 4925);
WIRE 17 -1 (700 4925)(700 5025);
WIRE 17 -1 (700 5025)(700 5125);
WIRE 17 -1 (700 5125)(700 5225);
WIRE 17 -1 (1500 5250)(700 5250);
FORCEPROP 2 LAST SIG_NAME M_F_DQS_DP<17:0>
J 0
(925 5260);
DISPLAY 0.617021 (925 5260);
PAINT ORANGE (925 5260);
WIRE 17 -1 (700 5250)(700 5225);
WIRE 17 -1 (-1500 1350)(-1500 1400);
WIRE 17 -1 (-1500 1400)(-1500 1450);
WIRE 17 -1 (-1500 1450)(-1500 1500);
WIRE 17 -1 (-1500 1500)(-1500 1550);
WIRE 17 -1 (-1500 1550)(-1500 1600);
WIRE 17 -1 (-1500 1600)(-1500 1650);
WIRE 17 -1 (-1500 1650)(-1500 1700);
WIRE 17 -1 (-1500 1700)(-1500 1750);
WIRE 17 -1 (-1500 1750)(-1500 1800);
WIRE 17 -1 (-1500 1800)(-1500 1850);
WIRE 17 -1 (-1500 1850)(-1500 1900);
WIRE 17 -1 (-1500 1900)(-1500 1950);
WIRE 17 -1 (-1500 1950)(-1500 2000);
WIRE 17 -1 (-1500 2000)(-1500 2050);
WIRE 17 -1 (-1500 2050)(-1500 2100);
WIRE 17 -1 (-1500 2100)(-1500 2150);
WIRE 17 -1 (-1500 2150)(-1500 2200);
WIRE 17 -1 (-1500 2200)(-1500 2250);
WIRE 17 -1 (-1500 2250)(-1500 2300);
WIRE 17 -1 (-1500 2300)(-1500 2350);
WIRE 17 -1 (-1500 2350)(-1500 2400);
WIRE 17 -1 (-1500 2400)(-1500 2450);
WIRE 17 -1 (-1500 2450)(-1500 2500);
WIRE 17 -1 (-1500 2500)(-1500 2550);
WIRE 17 -1 (-1500 2550)(-1500 2600);
WIRE 17 -1 (-1500 2600)(-1500 2650);
WIRE 17 -1 (-1500 2650)(-1500 2700);
WIRE 17 -1 (-1500 2700)(-1500 2750);
WIRE 17 -1 (-1500 2750)(-1500 2800);
WIRE 17 -1 (-1500 2800)(-1500 2850);
WIRE 17 -1 (-1500 2850)(-1500 2900);
WIRE 17 -1 (-1500 2900)(-1500 2950);
WIRE 17 -1 (-1500 2950)(-1500 3000);
WIRE 17 -1 (-1500 3000)(-1500 3050);
WIRE 17 -1 (-1500 3050)(-1500 3100);
WIRE 17 -1 (-1500 3100)(-1500 3150);
WIRE 17 -1 (-1500 3150)(-1500 3200);
WIRE 17 -1 (-1500 3200)(-1500 3250);
WIRE 17 -1 (-1500 3250)(-1500 3300);
WIRE 17 -1 (-1500 3300)(-1500 3350);
WIRE 17 -1 (-1500 3350)(-1500 3400);
WIRE 17 -1 (-1500 3400)(-1500 3450);
WIRE 17 -1 (-1500 3450)(-1500 3500);
WIRE 17 -1 (-1500 3500)(-1500 3550);
WIRE 17 -1 (-1500 3550)(-1500 3600);
WIRE 17 -1 (-1500 3600)(-1500 3650);
WIRE 17 -1 (-1500 3650)(-1500 3700);
WIRE 17 -1 (-1500 3700)(-1500 3750);
WIRE 17 -1 (-1500 3750)(-1500 3800);
WIRE 17 -1 (-1500 3800)(-1500 3850);
WIRE 17 -1 (-1500 3850)(-1500 3900);
WIRE 17 -1 (-1500 3900)(-1500 3950);
WIRE 17 -1 (-1500 3950)(-1500 4000);
WIRE 17 -1 (-1500 4000)(-1500 4050);
WIRE 17 -1 (-1500 4050)(-1500 4100);
WIRE 17 -1 (-1500 4100)(-1500 4150);
WIRE 17 -1 (-1500 4150)(-1500 4200);
WIRE 17 -1 (-1050 4525)(-1500 4525);
FORCEPROP 2 LAST SIG_NAME M_F_DQ<63:0>
J 0
(-1460 4535);
DISPLAY 0.617021 (-1460 4535);
PAINT ORANGE (-1460 4535);
WIRE 17 -1 (-1500 4500)(-1500 4525);
WIRE 17 -1 (-1500 4200)(-1500 4250);
WIRE 17 -1 (-1500 4250)(-1500 4300);
WIRE 17 -1 (-1500 4450)(-1500 4500);
WIRE 17 -1 (-1500 4400)(-1500 4450);
WIRE 17 -1 (-1500 4300)(-1500 4350);
WIRE 17 -1 (-1500 4350)(-1500 4400);
WIRE 17 -1 (-3100 3650)(-3100 3700);
WIRE 17 -1 (-3100 3700)(-3100 3750);
WIRE 17 -1 (-3100 3750)(-3100 3800);
WIRE 17 -1 (-3100 3800)(-3100 3850);
WIRE 17 -1 (-3100 3850)(-3100 3900);
WIRE 17 -1 (-3100 3900)(-3100 3950);
WIRE 17 -1 (-3100 3950)(-3100 4000);
WIRE 17 -1 (-3650 4525)(-3100 4525);
FORCEPROP 2 LAST SIG_NAME M_F_MA<17:0>
J 0
(-3625 4535);
DISPLAY 0.617021 (-3625 4535);
PAINT ORANGE (-3625 4535);
WIRE 17 -1 (-3100 4500)(-3100 4525);
WIRE 17 -1 (-3100 4000)(-3100 4050);
WIRE 17 -1 (-3100 4050)(-3100 4100);
WIRE 17 -1 (-3100 4450)(-3100 4500);
WIRE 17 -1 (-3100 4400)(-3100 4450);
WIRE 17 -1 (-3100 4100)(-3100 4150);
WIRE 17 -1 (-3100 4150)(-3100 4200);
WIRE 17 -1 (-3100 4350)(-3100 4400);
WIRE 17 -1 (-3100 4300)(-3100 4350);
WIRE 17 -1 (-3100 4200)(-3100 4250);
WIRE 17 -1 (-3100 4250)(-3100 4300);
WIRE 17 -1 (-3100 3500)(-3100 3550);
WIRE 17 -1 (-3100 3575)(-3650 3575);
FORCEPROP 2 LAST SIG_NAME M_F_BA<1:0>
J 0
(-3625 3585);
DISPLAY 0.617021 (-3625 3585);
PAINT ORANGE (-3625 3585);
WIRE 17 -1 (-3100 3575)(-3100 3550);
WIRE 17 -1 (-3100 3325)(-3650 3325);
FORCEPROP 2 LAST SIG_NAME M_F_CLK_DP<3:0>
J 0
(-3625 3335);
DISPLAY 0.617021 (-3625 3335);
PAINT ORANGE (-3625 3335);
WIRE 17 -1 (-3100 3325)(-3100 3300);
WIRE 17 -1 (-3100 3200)(-3100 3300);
WIRE 17 -1 (-3100 3450)(-3650 3450);
FORCEPROP 2 LAST SIG_NAME M_F_BG<1:0>
J 0
(-3625 3460);
DISPLAY 0.617021 (-3625 3460);
PAINT ORANGE (-3625 3460);
WIRE 17 -1 (-3100 3400)(-3100 3450);
WIRE 17 -1 (-3100 2850)(-3100 2900);
WIRE 17 -1 (-3100 2900)(-3100 2950);
WIRE 17 -1 (-3100 2950)(-3100 3000);
WIRE 17 -1 (-3100 3025)(-3650 3025);
FORCEPROP 2 LAST SIG_NAME M_F_CS_N<7:0>
J 0
(-3625 3035);
DISPLAY 0.617021 (-3625 3035);
PAINT ORANGE (-3625 3035);
WIRE 17 -1 (-3100 3025)(-3100 3000);
WIRE 17 -1 (-3100 2700)(-3100 2750);
WIRE 17 -1 (-3100 2775)(-3650 2775);
FORCEPROP 2 LAST SIG_NAME M_F_CKE<3:0>
J 0
(-3625 2785);
DISPLAY 0.617021 (-3625 2785);
PAINT ORANGE (-3625 2785);
WIRE 17 -1 (-3100 2775)(-3100 2750);
WIRE 17 -1 (-3100 2550)(-3100 2600);
WIRE 17 -1 (-3100 2625)(-3650 2625);
FORCEPROP 2 LAST SIG_NAME M_F_ODT<3:0>
J 0
(-3625 2635);
DISPLAY 0.617021 (-3625 2635);
PAINT ORANGE (-3625 2635);
WIRE 17 -1 (-3100 2625)(-3100 2600);
WIRE 17 -1 (-3100 2100)(-3100 2150);
WIRE 17 -1 (-3100 2150)(-3100 2200);
WIRE 17 -1 (-3100 2475)(-3650 2475);
FORCEPROP 2 LAST SIG_NAME M_F_ECC<7:0>
J 0
(-3625 2485);
DISPLAY 0.617021 (-3625 2485);
PAINT ORANGE (-3625 2485);
WIRE 17 -1 (-3100 2200)(-3100 2250);
WIRE 17 -1 (-3100 2250)(-3100 2300);
WIRE 17 -1 (-3100 2475)(-3100 2450);
WIRE 17 -1 (-3100 2400)(-3100 2450);
WIRE 17 -1 (-3100 2300)(-3100 2350);
WIRE 17 -1 (-3100 2350)(-3100 2400);
WIRE 17 -1 (-3300 3250)(-3300 3150);
WIRE 17 -1 (-3300 3275)(-3650 3275);
FORCEPROP 2 LAST SIG_NAME M_F_CLK_DN<3:0>
J 0
(-3625 3285);
DISPLAY 0.617021 (-3625 3285);
PAINT ORANGE (-3625 3285);
WIRE 17 -1 (-3300 3275)(-3300 3250);
WIRE 16 -1 (-3000 4025)(-2800 4025);
WIRE 16 -1 (-1600 2975)(-1800 2975);
WIRE 16 -1 (-1600 3025)(-1800 3025);
WIRE 16 -1 (-1600 3125)(-1800 3125);
WIRE 16 -1 (-1600 3275)(-1800 3275);
WIRE 16 -1 (-3000 4425)(-2800 4425);
WIRE 16 -1 (-3000 4175)(-2800 4175);
WIRE 16 -1 (-3000 4125)(-2800 4125);
WIRE 16 -1 (-1600 3375)(-1800 3375);
WIRE 16 -1 (-4500 1325)(-4500 1225);
WIRE 16 -1 (-4600 1325)(-4500 1325);
WIRE 16 -1 (-2800 1325)(-4500 1325);
FORCEPROP 2 LAST SIG_NAME M_F_VREF
J 0
(-3600 1335);
DISPLAY 0.617021 (-3600 1335);
PAINT ORANGE (-3600 1335);
WIRE 16 -1 (-3650 1175)(-2800 1175);
FORCEPROP 2 LAST SIG_NAME TP_CH_F_DIMM_F0_RFU_1
J 0
(-3600 1185);
DISPLAY 0.617021 (-3600 1185);
PAINT ORANGE (-3600 1185);
FORCEPROP 2 LASTPROP $XRERR UNIQUE?
J 0
(-3890 1175);
DISPLAY 0.638298 (-3890 1175);
PAINT MONO (-3890 1175);
DISPLAY INVISIBLE (-3890 1175);
WIRE 16 -1 (-3650 1125)(-2800 1125);
FORCEPROP 2 LAST SIG_NAME TP_CH_F_DIMM_F0_RFU_0
J 0
(-3600 1135);
DISPLAY 0.617021 (-3600 1135);
PAINT ORANGE (-3600 1135);
FORCEPROP 2 LASTPROP $XRERR UNIQUE?
J 0
(-3890 1125);
DISPLAY 0.638298 (-3890 1125);
PAINT MONO (-3890 1125);
DISPLAY INVISIBLE (-3890 1125);
WIRE 16 -1 (-3650 1225)(-2800 1225);
FORCEPROP 2 LAST SIG_NAME TP_CH_F_DIMM_F0_RFU_2
J 0
(-3600 1235);
DISPLAY 0.617021 (-3600 1235);
PAINT ORANGE (-3600 1235);
FORCEPROP 2 LASTPROP $XRERR UNIQUE?
J 0
(-3890 1225);
DISPLAY 0.638298 (-3890 1225);
PAINT MONO (-3890 1225);
DISPLAY INVISIBLE (-3890 1225);
WIRE 16 -1 (-2800 1775)(-3850 1775);
FORCEPROP 2 LAST SIG_NAME M_F_ACT_N
J 0
(-3800 1785);
DISPLAY 0.617021 (-3800 1785);
PAINT ORANGE (-3800 1785);
WIRE 16 -1 (-2800 1825)(-3875 1825);
FORCEPROP 2 LAST SIG_NAME M_F_ALERT_N
J 0
(-3825 1835);
DISPLAY 0.617021 (-3825 1835);
PAINT ORANGE (-3825 1835);
WIRE 16 -1 (-3650 1425)(-2800 1425);
FORCEPROP 2 LAST SIG_NAME SMB_DDR_DEF_VPP_SCL
J 0
(-3610 1435);
DISPLAY 0.617021 (-3610 1435);
PAINT ORANGE (-3610 1435);
WIRE 16 -1 (-3650 1475)(-2800 1475);
FORCEPROP 2 LAST SIG_NAME SMB_DDR_DEF_VPP_SDA
J 0
(-3610 1485);
DISPLAY 0.617021 (-3610 1485);
PAINT ORANGE (-3610 1485);
WIRE 16 -1 (-3650 1025)(-2800 1025);
FORCEPROP 2 LAST SIG_NAME FM_ADR_COMPLETE_DEF_N
J 0
(-3600 1035);
DISPLAY 0.617021 (-3600 1035);
PAINT ORANGE (-3600 1035);
WIRE 16 -1 (-2800 1925)(-3200 1925);
WIRE 16 -1 (-3200 1925)(-3200 2375);
WIRE 16 -1 (-3200 2375)(-3650 2375);
FORCEPROP 2 LAST SIG_NAME M_DEF_RST_N
J 0
(-3625 2385);
DISPLAY 0.617021 (-3625 2385);
PAINT ORANGE (-3625 2385);
WIRE 16 -1 (-3250 1875)(-2800 1875);
WIRE 16 -1 (-3250 1875)(-3250 2125);
WIRE 16 -1 (-3250 2125)(-3975 2125);
FORCEPROP 2 LAST SIG_NAME FM_DIMM_EVENT_COD_N
J 0
(-3937 2139);
DISPLAY 0.617021 (-3937 2139);
PAINT ORANGE (-3937 2139);
WIRE 16 -1 (-2800 1975)(-3150 1975);
WIRE 16 -1 (-3150 1975)(-3150 2425);
WIRE 16 -1 (-3150 2425)(-3650 2425);
FORCEPROP 2 LAST SIG_NAME M_F_PAR
J 0
(-3625 2435);
DISPLAY 0.617021 (-3625 2435);
PAINT ORANGE (-3625 2435);
WIRE 16 -1 (-3200 3125)(-2800 3125);
WIRE 16 -1 (-3200 3225)(-2800 3225);
WIRE 16 -1 (-3000 2525)(-2800 2525);
WIRE 16 -1 (-3000 2425)(-2800 2425);
WIRE 16 -1 (-3000 2075)(-2800 2075);
WIRE 16 -1 (-3000 2125)(-2800 2125);
WIRE 16 -1 (-3000 2175)(-2800 2175);
WIRE 16 -1 (-3000 2225)(-2800 2225);
WIRE 16 -1 (-3000 2275)(-2800 2275);
WIRE 16 -1 (-3000 2325)(-2800 2325);
WIRE 16 -1 (-3000 2375)(-2800 2375);
WIRE 16 -1 (-3000 2825)(-2800 2825);
WIRE 16 -1 (-3000 2675)(-2800 2675);
WIRE 16 -1 (-3000 2575)(-2800 2575);
WIRE 16 -1 (-3000 2725)(-2800 2725);
WIRE 16 -1 (-3000 2875)(-2800 2875);
WIRE 16 -1 (-3000 2925)(-2800 2925);
WIRE 16 -1 (-3000 2975)(-2800 2975);
WIRE 16 -1 (-3650 3075)(-2950 3075);
FORCEPROP 2 LAST SIG_NAME M_F_C<2>
J 0
(-3625 3085);
DISPLAY 0.617021 (-3625 3085);
PAINT ORANGE (-3625 3085);
WIRE 16 -1 (-2950 3025)(-2950 3075);
WIRE 16 -1 (-2800 3025)(-2950 3025);
WIRE 16 -1 (-3000 3475)(-2800 3475);
WIRE 16 -1 (-3000 3425)(-2800 3425);
WIRE 16 -1 (-3000 3375)(-2800 3375);
WIRE 16 -1 (-3000 3275)(-2800 3275);
WIRE 16 -1 (-3000 3175)(-2800 3175);
WIRE 16 -1 (-3000 3525)(-2800 3525);
WIRE 16 -1 (-3000 3725)(-2800 3725);
WIRE 16 -1 (-3000 4075)(-2800 4075);
WIRE 16 -1 (-3000 3975)(-2800 3975);
WIRE 16 -1 (-3000 3925)(-2800 3925);
WIRE 16 -1 (-3000 3875)(-2800 3875);
WIRE 16 -1 (-3000 3825)(-2800 3825);
WIRE 16 -1 (-3000 3775)(-2800 3775);
WIRE 16 -1 (-3000 3675)(-2800 3675);
WIRE 16 -1 (-3000 3625)(-2800 3625);
WIRE 16 -1 (-1600 1525)(-1800 1525);
WIRE 16 -1 (-1600 1475)(-1800 1475);
WIRE 16 -1 (-1600 1425)(-1800 1425);
WIRE 16 -1 (-1600 1325)(-1800 1325);
WIRE 16 -1 (-1600 1375)(-1800 1375);
WIRE 16 -1 (-1600 1575)(-1800 1575);
WIRE 16 -1 (-1600 1625)(-1800 1625);
WIRE 16 -1 (-1600 1675)(-1800 1675);
WIRE 16 -1 (-1600 1725)(-1800 1725);
WIRE 16 -1 (-1600 1775)(-1800 1775);
WIRE 16 -1 (-1600 1875)(-1800 1875);
WIRE 16 -1 (-1600 1975)(-1800 1975);
WIRE 16 -1 (-1600 2025)(-1800 2025);
WIRE 16 -1 (-1600 1825)(-1800 1825);
WIRE 16 -1 (-1600 1925)(-1800 1925);
WIRE 16 -1 (-1600 2175)(-1800 2175);
WIRE 16 -1 (-1600 2075)(-1800 2075);
WIRE 16 -1 (-1600 2125)(-1800 2125);
WIRE 16 -1 (-1600 2375)(-1800 2375);
WIRE 16 -1 (-1600 2425)(-1800 2425);
WIRE 16 -1 (-1600 2475)(-1800 2475);
WIRE 16 -1 (-1600 2225)(-1800 2225);
WIRE 16 -1 (-1600 2275)(-1800 2275);
WIRE 16 -1 (-1600 2325)(-1800 2325);
WIRE 16 -1 (-1600 2525)(-1800 2525);
WIRE 16 -1 (-1600 2625)(-1800 2625);
WIRE 16 -1 (-1600 2675)(-1800 2675);
WIRE 16 -1 (-1600 2575)(-1800 2575);
WIRE 16 -1 (-1600 2825)(-1800 2825);
WIRE 16 -1 (-1600 2875)(-1800 2875);
WIRE 16 -1 (-1600 2925)(-1800 2925);
WIRE 16 -1 (-1600 2725)(-1800 2725);
WIRE 16 -1 (-1600 2775)(-1800 2775);
WIRE 16 -1 (-1600 3225)(-1800 3225);
WIRE 16 -1 (-1600 3075)(-1800 3075);
WIRE 16 -1 (-1600 3175)(-1800 3175);
WIRE 16 -1 (-1600 3325)(-1800 3325);
WIRE 16 -1 (-1600 3425)(-1800 3425);
WIRE 16 -1 (-1600 3475)(-1800 3475);
WIRE 16 -1 (-1600 3525)(-1800 3525);
WIRE 16 -1 (-1600 3575)(-1800 3575);
WIRE 16 -1 (-1600 3675)(-1800 3675);
WIRE 16 -1 (-1600 3725)(-1800 3725);
WIRE 16 -1 (-1600 3775)(-1800 3775);
WIRE 16 -1 (-1600 3825)(-1800 3825);
WIRE 16 -1 (-1600 3875)(-1800 3875);
WIRE 16 -1 (-1600 3925)(-1800 3925);
WIRE 16 -1 (-1600 3975)(-1800 3975);
WIRE 16 -1 (-1600 4025)(-1800 4025);
WIRE 16 -1 (-1600 3625)(-1800 3625);
WIRE 16 -1 (-1600 4075)(-1800 4075);
WIRE 16 -1 (-3000 4375)(-2800 4375);
WIRE 16 -1 (-3000 4325)(-2800 4325);
WIRE 16 -1 (-3000 4475)(-2800 4475);
WIRE 16 -1 (-3000 4275)(-2800 4275);
WIRE 16 -1 (-3000 4225)(-2800 4225);
WIRE 16 -1 (-1600 4475)(-1800 4475);
WIRE 16 -1 (-1600 4425)(-1800 4425);
WIRE 16 -1 (-1600 4375)(-1800 4375);
WIRE 16 -1 (-1600 4225)(-1800 4225);
WIRE 16 -1 (-1600 4175)(-1800 4175);
WIRE 16 -1 (-1600 4125)(-1800 4125);
WIRE 16 -1 (-1600 4275)(-1800 4275);
WIRE 16 -1 (-1600 4325)(-1800 4325);
WIRE 16 -1 (800 4050)(400 4050);
WIRE 16 -1 (600 4000)(400 4000);
WIRE 16 -1 (800 3950)(400 3950);
WIRE 16 -1 (600 3900)(400 3900);
WIRE 16 -1 (800 3850)(400 3850);
WIRE 16 -1 (600 3800)(400 3800);
WIRE 16 -1 (800 3750)(400 3750);
WIRE 16 -1 (600 3700)(400 3700);
WIRE 16 -1 (800 3650)(400 3650);
WIRE 16 -1 (600 3600)(400 3600);
WIRE 16 -1 (800 3550)(400 3550);
WIRE 16 -1 (600 3500)(400 3500);
WIRE 16 -1 (800 3450)(400 3450);
WIRE 16 -1 (600 4400)(400 4400);
WIRE 16 -1 (800 4350)(400 4350);
WIRE 16 -1 (600 4300)(400 4300);
WIRE 16 -1 (800 4250)(400 4250);
WIRE 16 -1 (600 4200)(400 4200);
WIRE 16 -1 (800 4150)(400 4150);
WIRE 16 -1 (600 4100)(400 4100);
WIRE 16 -1 (600 5100)(400 5100);
WIRE 16 -1 (800 5050)(400 5050);
WIRE 16 -1 (600 5000)(400 5000);
WIRE 16 -1 (800 4950)(400 4950);
WIRE 16 -1 (600 4900)(400 4900);
WIRE 16 -1 (800 4850)(400 4850);
WIRE 16 -1 (600 4800)(400 4800);
WIRE 16 -1 (800 4750)(400 4750);
WIRE 16 -1 (600 4700)(400 4700);
WIRE 16 -1 (800 4650)(400 4650);
WIRE 16 -1 (600 4600)(400 4600);
WIRE 16 -1 (800 4550)(400 4550);
WIRE 16 -1 (600 4500)(400 4500);
WIRE 16 -1 (800 4450)(400 4450);
WIRE 16 -1 (600 5200)(400 5200);
WIRE 16 -1 (800 5150)(400 5150);
DOT 1 (-3025 1575);
DOT 1 (-3025 1675);
DOT 1 (-950 2850);
DOT 1 (-950 2800);
DOT 1 (-950 2750);
DOT 1 (1050 2250);
DOT 1 (2450 3500);
DOT 1 (1050 3500);
DOT 1 (2450 3450);
DOT 1 (2450 3400);
DOT 1 (2450 3350);
DOT 1 (2450 3300);
DOT 1 (2450 3250);
DOT 1 (2450 3200);
DOT 1 (2450 3150);
DOT 1 (2450 3100);
DOT 1 (2450 3000);
DOT 1 (2450 3050);
DOT 1 (2450 2950);
DOT 1 (2450 2900);
DOT 1 (2450 2850);
DOT 1 (2450 2800);
DOT 1 (2450 2750);
DOT 1 (2450 2700);
DOT 1 (2450 2650);
DOT 1 (2450 2600);
DOT 1 (2450 2550);
DOT 1 (2450 2500);
DOT 1 (2450 2400);
DOT 1 (2450 2450);
DOT 1 (2450 2350);
DOT 1 (2450 2300);
DOT 1 (2450 2250);
DOT 1 (2450 2150);
DOT 1 (2450 2200);
DOT 1 (2450 2100);
DOT 1 (2450 2050);
DOT 1 (2450 1950);
DOT 1 (2450 1850);
DOT 1 (2450 1900);
DOT 1 (2450 1800);
DOT 1 (2450 1750);
DOT 1 (2450 1600);
DOT 1 (2450 1700);
DOT 1 (2450 1650);
DOT 1 (2450 1550);
DOT 1 (2450 1500);
DOT 1 (2450 1450);
DOT 1 (2450 1400);
DOT 1 (2450 1350);
DOT 1 (2450 1300);
DOT 1 (2450 1250);
DOT 1 (1050 3400);
DOT 1 (1050 3450);
DOT 1 (1050 3350);
DOT 1 (1050 3300);
DOT 1 (1050 3250);
DOT 1 (1050 3150);
DOT 1 (1050 3200);
DOT 1 (1050 3000);
DOT 1 (1050 3050);
DOT 1 (1050 3100);
DOT 1 (1050 2900);
DOT 1 (1050 2950);
DOT 1 (1050 2850);
DOT 1 (1050 2800);
DOT 1 (1050 2750);
DOT 1 (1050 2650);
DOT 1 (1050 2700);
DOT 1 (1050 2500);
DOT 1 (1050 2550);
DOT 1 (1050 2600);
DOT 1 (1050 2450);
DOT 1 (1050 2400);
DOT 1 (1050 2350);
DOT 1 (1050 2300);
DOT 1 (1050 2200);
DOT 1 (1050 2150);
DOT 1 (1050 2100);
DOT 1 (1050 2000);
DOT 1 (1050 2050);
DOT 1 (1050 1950);
DOT 1 (1050 1900);
DOT 1 (1050 1850);
DOT 1 (1050 1750);
DOT 1 (1050 1800);
DOT 1 (1050 1700);
DOT 1 (1050 1650);
DOT 1 (1050 1600);
DOT 1 (1050 1550);
DOT 1 (1050 1500);
DOT 1 (1050 1450);
DOT 1 (1050 1350);
DOT 1 (1050 1400);
DOT 1 (1050 1250);
DOT 1 (1050 1300);
DOT 1 (-950 2900);
DOT 1 (-900 2350);
DOT 1 (-900 2400);
DOT 1 (-900 2450);
DOT 1 (-900 2300);
DOT 1 (-900 2250);
DOT 1 (-950 2600);
DOT 1 (-900 2200);
DOT 1 (-900 2150);
DOT 1 (-900 1950);
DOT 1 (-900 1900);
DOT 1 (-900 1850);
DOT 1 (-900 1750);
DOT 1 (-900 1700);
DOT 1 (-900 1650);
DOT 1 (-900 1600);
DOT 1 (-900 1550);
DOT 1 (-900 1500);
DOT 1 (-900 1450);
DOT 1 (-900 1350);
DOT 1 (-900 1400);
DOT 1 (-900 1250);
DOT 1 (-900 1300);
DOT 1 (-900 1800);
DOT 1 (-900 2000);
DOT 1 (-900 2050);
DOT 1 (-900 2100);
DOT 1 (-4500 1325);
DOT 1 (2450 2000);
DOT 1 (450 2900);
FORCENOTE
PVDDQ (SINGLE SIDE) CAP: 10UF X1, 22UF X50
(-3050 5150) 0;
DISPLAY LEFT (-3050 5150);
DISPLAY 1.021277 (-3050 5150);
PAINT PURPLE (-3050 5150);
FORCENOTE
PVTT CAP: 100UF X2, 47UF X1
(-3050 5200) 0;
DISPLAY LEFT (-3050 5200);
DISPLAY 1.021277 (-3050 5200);
PAINT PURPLE (-3050 5200);
FORCENOTE
PVDDQ (DOUBLE SIDE) CAP: 100UF X8, 47UF X41
(-3050 5100) 0;
DISPLAY LEFT (-3050 5100);
DISPLAY 1.021277 (-3050 5100);
PAINT PURPLE (-3050 5100);
FORCENOTE
PLACE CAP NEAR DIMM CONNECTOR
(-4388 877) 0;
DISPLAY LEFT (-4388 877);
DISPLAY 1.021277 (-4388 877);
PAINT PURPLE (-4388 877);
FORCENOTE
SMBUS ADDR: 0XA8
(-5300 734) 0;
DISPLAY LEFT (-5300 734);
DISPLAY 1.574468 (-5300 734);
PAINT PURPLE (-5300 734);
FORCENOTE
PVPP CAP: 10UF X12
(-3050 5250) 0;
DISPLAY LEFT (-3050 5250);
DISPLAY 1.021277 (-3050 5250);
PAINT PURPLE (-3050 5250);
FORCENOTE
CAP BETWEEN DIMM
(-3050 5325) 0;
DISPLAY LEFT (-3050 5325);
DISPLAY 1.276596 (-3050 5325);
PAINT PURPLE (-3050 5325);
QUIT
